G04*
G04 #@! TF.GenerationSoftware,Altium Limited,Altium Designer,23.0.1 (38)*
G04*
G04 Layer_Physical_Order=5*
G04 Layer_Color=16737945*
%FSLAX25Y25*%
%MOIN*%
G70*
G04*
G04 #@! TF.SameCoordinates,C48E81DB-6E20-4E2D-80E6-7C5AFAA1A21F*
G04*
G04*
G04 #@! TF.FilePolarity,Positive*
G04*
G01*
G75*
G04:AMPARAMS|DCode=212|XSize=43.31mil|YSize=70.87mil|CornerRadius=21.65mil|HoleSize=0mil|Usage=FLASHONLY|Rotation=90.000|XOffset=0mil|YOffset=0mil|HoleType=Round|Shape=RoundedRectangle|*
%AMROUNDEDRECTD212*
21,1,0.04331,0.02756,0,0,90.0*
21,1,0.00000,0.07087,0,0,90.0*
1,1,0.04331,0.01378,0.00000*
1,1,0.04331,0.01378,0.00000*
1,1,0.04331,-0.01378,0.00000*
1,1,0.04331,-0.01378,0.00000*
%
%ADD212ROUNDEDRECTD212*%
G04:AMPARAMS|DCode=213|XSize=47.24mil|YSize=62.99mil|CornerRadius=23.62mil|HoleSize=0mil|Usage=FLASHONLY|Rotation=90.000|XOffset=0mil|YOffset=0mil|HoleType=Round|Shape=RoundedRectangle|*
%AMROUNDEDRECTD213*
21,1,0.04724,0.01575,0,0,90.0*
21,1,0.00000,0.06299,0,0,90.0*
1,1,0.04724,0.00787,0.00000*
1,1,0.04724,0.00787,0.00000*
1,1,0.04724,-0.00787,0.00000*
1,1,0.04724,-0.00787,0.00000*
%
%ADD213ROUNDEDRECTD213*%
%ADD215R,0.10827X0.10827*%
%ADD216C,0.10827*%
%ADD240C,0.06102*%
%ADD241C,0.10000*%
%ADD245C,0.08661*%
%ADD248C,0.05906*%
%ADD250C,0.01600*%
%ADD251C,0.05000*%
%ADD253C,0.01968*%
G36*
X24429Y20107D02*
X24747Y19721D01*
X24739Y19685D01*
X24879Y18983D01*
X25277Y18387D01*
X25872Y17989D01*
X26575Y17850D01*
X27277Y17989D01*
X27872Y18387D01*
X28270Y18983D01*
X28410Y19685D01*
X28403Y19721D01*
X28720Y20107D01*
X31404D01*
X31629Y19833D01*
X31769Y19131D01*
X32167Y18535D01*
X32762Y18137D01*
X33465Y17998D01*
X34167Y18137D01*
X34762Y18535D01*
X35160Y19131D01*
X35300Y19833D01*
X35525Y20107D01*
X38209D01*
X38526Y19721D01*
X38519Y19685D01*
X38659Y18983D01*
X39057Y18387D01*
X39652Y17989D01*
X40354Y17850D01*
X41057Y17989D01*
X41652Y18387D01*
X42050Y18983D01*
X42190Y19685D01*
X42182Y19721D01*
X42500Y20107D01*
X45099D01*
X45416Y19721D01*
X45409Y19685D01*
X45548Y18983D01*
X45946Y18387D01*
X46542Y17989D01*
X47244Y17850D01*
X47946Y17989D01*
X48542Y18387D01*
X48940Y18983D01*
X49079Y19685D01*
X49072Y19721D01*
X49389Y20107D01*
X206862Y20107D01*
X699564Y20107D01*
X699564Y-363786D01*
X283662D01*
X283193Y-363879D01*
X282796Y-364144D01*
X282531Y-364541D01*
X282501Y-364693D01*
X282449D01*
X282438Y-365009D01*
X282438Y-365188D01*
Y-392667D01*
X201420D01*
Y-385876D01*
X201412Y-385836D01*
X201418Y-385796D01*
X201386Y-385307D01*
X201355Y-385191D01*
X201347Y-385071D01*
X201094Y-384128D01*
X201023Y-383984D01*
X200972Y-383833D01*
X200483Y-382987D01*
X200378Y-382867D01*
X200289Y-382734D01*
X199599Y-382043D01*
X199466Y-381954D01*
X199345Y-381849D01*
X198500Y-381361D01*
X198348Y-381309D01*
X198205Y-381238D01*
X197262Y-380986D01*
X197102Y-380975D01*
X196945Y-380944D01*
X195968D01*
X195812Y-380975D01*
X195652Y-380986D01*
X195625Y-380993D01*
X194449D01*
X193627Y-381815D01*
X193568Y-381849D01*
X193448Y-381954D01*
X193315Y-382043D01*
X192624Y-382734D01*
X192535Y-382867D01*
X192430Y-382987D01*
X192396Y-383046D01*
X191249Y-384193D01*
Y-392667D01*
X149846D01*
Y-372195D01*
X149840Y-372165D01*
X149844Y-372134D01*
X149809Y-371430D01*
X149787Y-371342D01*
Y-371252D01*
X149513Y-369870D01*
X149467Y-369759D01*
X149443Y-369641D01*
X149149Y-368931D01*
Y-368693D01*
X148981Y-368525D01*
X148904Y-368339D01*
X148837Y-368239D01*
X148791Y-368128D01*
X148008Y-366957D01*
X147923Y-366871D01*
X147856Y-366771D01*
X146860Y-365775D01*
X146760Y-365708D01*
X146675Y-365623D01*
X145504Y-364841D01*
X145392Y-364794D01*
X145292Y-364727D01*
X145107Y-364651D01*
X144549Y-364093D01*
X143631D01*
X142380Y-363844D01*
X142259D01*
X142141Y-363821D01*
X140733D01*
X140615Y-363844D01*
X140494D01*
X139243Y-364093D01*
X137349D01*
X132849Y-368593D01*
Y-382888D01*
X103979D01*
Y-365009D01*
X103886Y-364541D01*
X103621Y-364144D01*
X103224Y-363879D01*
X102756Y-363786D01*
X30512D01*
X30044Y-363879D01*
X29647Y-364144D01*
X29481Y-364393D01*
X29149D01*
Y-396266D01*
X-27320D01*
Y20107D01*
X24429D01*
D02*
G37*
%LPC*%
G36*
X593008Y17890D02*
X585102D01*
Y9984D01*
X593008D01*
Y17890D01*
D02*
G37*
G36*
X579055Y17924D02*
X578023Y17788D01*
X577062Y17390D01*
X576236Y16756D01*
X575602Y15930D01*
X575204Y14969D01*
X575068Y13937D01*
X575204Y12905D01*
X575602Y11944D01*
X576236Y11118D01*
X577062Y10484D01*
X578023Y10086D01*
X579055Y9950D01*
X580087Y10086D01*
X581048Y10484D01*
X581874Y11118D01*
X582508Y11944D01*
X582906Y12905D01*
X583042Y13937D01*
X582906Y14969D01*
X582508Y15930D01*
X581874Y16756D01*
X581048Y17390D01*
X580087Y17788D01*
X579055Y17924D01*
D02*
G37*
G36*
X569055D02*
X568023Y17788D01*
X567062Y17390D01*
X566236Y16756D01*
X565602Y15930D01*
X565204Y14969D01*
X565068Y13937D01*
X565204Y12905D01*
X565602Y11944D01*
X566236Y11118D01*
X567062Y10484D01*
X568023Y10086D01*
X569055Y9950D01*
X570087Y10086D01*
X571048Y10484D01*
X571874Y11118D01*
X572508Y11944D01*
X572906Y12905D01*
X573042Y13937D01*
X572906Y14969D01*
X572508Y15930D01*
X571874Y16756D01*
X571048Y17390D01*
X570087Y17788D01*
X569055Y17924D01*
D02*
G37*
G36*
X559055D02*
X558023Y17788D01*
X557062Y17390D01*
X556236Y16756D01*
X555602Y15930D01*
X555204Y14969D01*
X555068Y13937D01*
X555204Y12905D01*
X555602Y11944D01*
X556236Y11118D01*
X557062Y10484D01*
X558023Y10086D01*
X559055Y9950D01*
X560087Y10086D01*
X561049Y10484D01*
X561874Y11118D01*
X562508Y11944D01*
X562906Y12905D01*
X563042Y13937D01*
X562906Y14969D01*
X562508Y15930D01*
X561874Y16756D01*
X561049Y17390D01*
X560087Y17788D01*
X559055Y17924D01*
D02*
G37*
G36*
X539055D02*
X538023Y17788D01*
X537062Y17390D01*
X536236Y16756D01*
X535602Y15930D01*
X535204Y14969D01*
X535068Y13937D01*
X535204Y12905D01*
X535602Y11944D01*
X536236Y11118D01*
X537062Y10484D01*
X538023Y10086D01*
X539055Y9950D01*
X540087Y10086D01*
X541048Y10484D01*
X541874Y11118D01*
X542508Y11944D01*
X542906Y12905D01*
X543042Y13937D01*
X542906Y14969D01*
X542508Y15930D01*
X541874Y16756D01*
X541048Y17390D01*
X540087Y17788D01*
X539055Y17924D01*
D02*
G37*
G36*
X589055Y7924D02*
X588023Y7788D01*
X587062Y7390D01*
X586236Y6756D01*
X585602Y5930D01*
X585204Y4969D01*
X585068Y3937D01*
X585204Y2905D01*
X585602Y1944D01*
X586236Y1118D01*
X587062Y484D01*
X588023Y86D01*
X589055Y-50D01*
X590087Y86D01*
X591048Y484D01*
X591874Y1118D01*
X592508Y1944D01*
X592906Y2905D01*
X593042Y3937D01*
X592906Y4969D01*
X592508Y5930D01*
X591874Y6756D01*
X591048Y7390D01*
X590087Y7788D01*
X589055Y7924D01*
D02*
G37*
G36*
X579055D02*
X578023Y7788D01*
X577062Y7390D01*
X576236Y6756D01*
X575602Y5930D01*
X575204Y4969D01*
X575068Y3937D01*
X575204Y2905D01*
X575602Y1944D01*
X576236Y1118D01*
X577062Y484D01*
X578023Y86D01*
X579055Y-50D01*
X580087Y86D01*
X581048Y484D01*
X581874Y1118D01*
X582508Y1944D01*
X582906Y2905D01*
X583042Y3937D01*
X582906Y4969D01*
X582508Y5930D01*
X581874Y6756D01*
X581048Y7390D01*
X580087Y7788D01*
X579055Y7924D01*
D02*
G37*
G36*
X569055D02*
X568023Y7788D01*
X567062Y7390D01*
X566236Y6756D01*
X565602Y5930D01*
X565204Y4969D01*
X565068Y3937D01*
X565204Y2905D01*
X565602Y1944D01*
X566236Y1118D01*
X567062Y484D01*
X568023Y86D01*
X569055Y-50D01*
X570087Y86D01*
X571048Y484D01*
X571874Y1118D01*
X572508Y1944D01*
X572906Y2905D01*
X573042Y3937D01*
X572906Y4969D01*
X572508Y5930D01*
X571874Y6756D01*
X571048Y7390D01*
X570087Y7788D01*
X569055Y7924D01*
D02*
G37*
G36*
X559055D02*
X558023Y7788D01*
X557062Y7390D01*
X556236Y6756D01*
X555602Y5930D01*
X555204Y4969D01*
X555068Y3937D01*
X555204Y2905D01*
X555602Y1944D01*
X556236Y1118D01*
X557062Y484D01*
X558023Y86D01*
X559055Y-50D01*
X560087Y86D01*
X561049Y484D01*
X561874Y1118D01*
X562508Y1944D01*
X562906Y2905D01*
X563042Y3937D01*
X562906Y4969D01*
X562508Y5930D01*
X561874Y6756D01*
X561049Y7390D01*
X560087Y7788D01*
X559055Y7924D01*
D02*
G37*
G36*
X539055D02*
X538023Y7788D01*
X537062Y7390D01*
X536236Y6756D01*
X535602Y5930D01*
X535204Y4969D01*
X535068Y3937D01*
X535204Y2905D01*
X535602Y1944D01*
X536236Y1118D01*
X537062Y484D01*
X538023Y86D01*
X539055Y-50D01*
X540087Y86D01*
X541048Y484D01*
X541874Y1118D01*
X542508Y1944D01*
X542906Y2905D01*
X543042Y3937D01*
X542906Y4969D01*
X542508Y5930D01*
X541874Y6756D01*
X541048Y7390D01*
X540087Y7788D01*
X539055Y7924D01*
D02*
G37*
G36*
X310069Y18446D02*
X308343Y18310D01*
X306659Y17906D01*
X305060Y17243D01*
X303583Y16339D01*
X302267Y15214D01*
X301142Y13897D01*
X300238Y12421D01*
X299575Y10821D01*
X299171Y9138D01*
X299035Y7412D01*
X299171Y5686D01*
X299575Y4002D01*
X300238Y2402D01*
X301142Y926D01*
X302267Y-390D01*
X303583Y-1515D01*
X305060Y-2420D01*
X306659Y-3082D01*
X308343Y-3486D01*
X310069Y-3622D01*
X311795Y-3486D01*
X313479Y-3082D01*
X315078Y-2420D01*
X316555Y-1515D01*
X317871Y-390D01*
X318996Y926D01*
X319900Y2402D01*
X320563Y4002D01*
X320967Y5686D01*
X321103Y7412D01*
X320967Y9138D01*
X320563Y10821D01*
X319900Y12421D01*
X318996Y13897D01*
X317871Y15214D01*
X316555Y16339D01*
X315078Y17243D01*
X313479Y17906D01*
X311795Y18310D01*
X310069Y18446D01*
D02*
G37*
G36*
X71880D02*
X70154Y18310D01*
X68470Y17906D01*
X66871Y17243D01*
X65394Y16339D01*
X64078Y15214D01*
X62953Y13897D01*
X62049Y12421D01*
X61386Y10821D01*
X60982Y9138D01*
X60846Y7412D01*
X60982Y5686D01*
X61386Y4002D01*
X62049Y2402D01*
X62953Y926D01*
X64078Y-390D01*
X65394Y-1515D01*
X66871Y-2420D01*
X68470Y-3082D01*
X70154Y-3486D01*
X71880Y-3622D01*
X73606Y-3486D01*
X75290Y-3082D01*
X76889Y-2420D01*
X78366Y-1515D01*
X79682Y-390D01*
X80807Y926D01*
X81711Y2402D01*
X82374Y4002D01*
X82778Y5686D01*
X82914Y7412D01*
X82778Y9138D01*
X82374Y10821D01*
X81711Y12421D01*
X80807Y13897D01*
X79682Y15214D01*
X78366Y16339D01*
X76889Y17243D01*
X75290Y17906D01*
X73606Y18310D01*
X71880Y18446D01*
D02*
G37*
G36*
X651545Y18288D02*
X649819Y18153D01*
X648136Y17748D01*
X646536Y17086D01*
X645060Y16181D01*
X643743Y15057D01*
X642619Y13740D01*
X641714Y12264D01*
X641051Y10664D01*
X640647Y8980D01*
X640511Y7254D01*
X640647Y5528D01*
X641051Y3845D01*
X641714Y2245D01*
X642619Y769D01*
X643743Y-548D01*
X645060Y-1672D01*
X646536Y-2577D01*
X648136Y-3240D01*
X649819Y-3644D01*
X651545Y-3780D01*
X653271Y-3644D01*
X654955Y-3240D01*
X656555Y-2577D01*
X658031Y-1672D01*
X659347Y-548D01*
X660472Y769D01*
X661377Y2245D01*
X662039Y3845D01*
X662443Y5528D01*
X662579Y7254D01*
X662443Y8980D01*
X662039Y10664D01*
X661377Y12264D01*
X660472Y13740D01*
X659347Y15057D01*
X658031Y16181D01*
X656555Y17086D01*
X654955Y17748D01*
X653271Y18153D01*
X651545Y18288D01*
D02*
G37*
G36*
X413356D02*
X411630Y18153D01*
X409947Y17748D01*
X408347Y17086D01*
X406871Y16181D01*
X405554Y15057D01*
X404430Y13740D01*
X403525Y12264D01*
X402862Y10664D01*
X402458Y8980D01*
X402322Y7254D01*
X402458Y5528D01*
X402862Y3845D01*
X403525Y2245D01*
X404430Y769D01*
X405554Y-548D01*
X406871Y-1672D01*
X408347Y-2577D01*
X409947Y-3240D01*
X411630Y-3644D01*
X413356Y-3780D01*
X415082Y-3644D01*
X416766Y-3240D01*
X418366Y-2577D01*
X419842Y-1672D01*
X421159Y-548D01*
X422283Y769D01*
X423188Y2245D01*
X423850Y3845D01*
X424254Y5528D01*
X424390Y7254D01*
X424254Y8980D01*
X423850Y10664D01*
X423188Y12264D01*
X422283Y13740D01*
X421159Y15057D01*
X419842Y16181D01*
X418366Y17086D01*
X416766Y17748D01*
X415082Y18153D01*
X413356Y18288D01*
D02*
G37*
G36*
X615158Y-7023D02*
X614455Y-7163D01*
X613860Y-7561D01*
X613462Y-8156D01*
X613322Y-8858D01*
X613462Y-9561D01*
X613860Y-10156D01*
X614455Y-10554D01*
X615158Y-10694D01*
X615860Y-10554D01*
X616455Y-10156D01*
X616853Y-9561D01*
X616993Y-8858D01*
X616853Y-8156D01*
X616455Y-7561D01*
X615860Y-7163D01*
X615158Y-7023D01*
D02*
G37*
G36*
X47244D02*
X46542Y-7163D01*
X45946Y-7561D01*
X45548Y-8156D01*
X45409Y-8858D01*
X45548Y-9561D01*
X45946Y-10156D01*
X46542Y-10554D01*
X47244Y-10694D01*
X47946Y-10554D01*
X48542Y-10156D01*
X48940Y-9561D01*
X49079Y-8858D01*
X48940Y-8156D01*
X48542Y-7561D01*
X47946Y-7163D01*
X47244Y-7023D01*
D02*
G37*
G36*
X40354D02*
X39652Y-7163D01*
X39057Y-7561D01*
X38659Y-8156D01*
X38519Y-8858D01*
X38659Y-9561D01*
X39057Y-10156D01*
X39652Y-10554D01*
X40354Y-10694D01*
X41057Y-10554D01*
X41652Y-10156D01*
X42050Y-9561D01*
X42190Y-8858D01*
X42050Y-8156D01*
X41652Y-7561D01*
X41057Y-7163D01*
X40354Y-7023D01*
D02*
G37*
G36*
X33465D02*
X32762Y-7163D01*
X32167Y-7561D01*
X31769Y-8156D01*
X31629Y-8858D01*
X31769Y-9561D01*
X32167Y-10156D01*
X32762Y-10554D01*
X33465Y-10694D01*
X34167Y-10554D01*
X34762Y-10156D01*
X35160Y-9561D01*
X35300Y-8858D01*
X35160Y-8156D01*
X34762Y-7561D01*
X34167Y-7163D01*
X33465Y-7023D01*
D02*
G37*
G36*
X26495Y-7156D02*
X25793Y-7296D01*
X25198Y-7694D01*
X24800Y-8289D01*
X24660Y-8991D01*
X24800Y-9694D01*
X25198Y-10289D01*
X25793Y-10687D01*
X26495Y-10827D01*
X27198Y-10687D01*
X27793Y-10289D01*
X28191Y-9694D01*
X28330Y-8991D01*
X28191Y-8289D01*
X27793Y-7694D01*
X27198Y-7296D01*
X26495Y-7156D01*
D02*
G37*
G36*
X685039Y13542D02*
X682921Y13375D01*
X680855Y12879D01*
X678892Y12066D01*
X677080Y10955D01*
X675464Y9576D01*
X674084Y7960D01*
X672974Y6148D01*
X672160Y4185D01*
X671664Y2118D01*
X671498Y0D01*
X671664Y-2118D01*
X672160Y-4185D01*
X672974Y-6148D01*
X674084Y-7960D01*
X675464Y-9576D01*
X677080Y-10955D01*
X678892Y-12066D01*
X680855Y-12879D01*
X682921Y-13375D01*
X685039Y-13542D01*
X687158Y-13375D01*
X689224Y-12879D01*
X691187Y-12066D01*
X692999Y-10955D01*
X694615Y-9576D01*
X695995Y-7960D01*
X697105Y-6148D01*
X697918Y-4185D01*
X698414Y-2118D01*
X698581Y0D01*
X698414Y2118D01*
X697918Y4185D01*
X697105Y6148D01*
X695995Y7960D01*
X694615Y9576D01*
X692999Y10955D01*
X691187Y12066D01*
X689224Y12879D01*
X687158Y13375D01*
X685039Y13542D01*
D02*
G37*
G36*
X0D02*
X-2118Y13375D01*
X-4185Y12879D01*
X-6148Y12066D01*
X-7960Y10955D01*
X-9576Y9576D01*
X-10955Y7960D01*
X-12066Y6148D01*
X-12879Y4185D01*
X-13375Y2118D01*
X-13542Y0D01*
X-13375Y-2118D01*
X-12879Y-4185D01*
X-12066Y-6148D01*
X-10955Y-7960D01*
X-9576Y-9576D01*
X-7960Y-10955D01*
X-6148Y-12066D01*
X-4185Y-12879D01*
X-2118Y-13375D01*
X0Y-13542D01*
X2118Y-13375D01*
X4185Y-12879D01*
X6148Y-12066D01*
X7960Y-10955D01*
X9576Y-9576D01*
X10955Y-7960D01*
X12066Y-6148D01*
X12879Y-4185D01*
X13375Y-2118D01*
X13542Y0D01*
X13375Y2118D01*
X12879Y4185D01*
X12066Y6148D01*
X10955Y7960D01*
X9576Y9576D01*
X7960Y10955D01*
X6148Y12066D01*
X4185Y12879D01*
X2118Y13375D01*
X0Y13542D01*
D02*
G37*
G36*
X660236Y-13125D02*
X659534Y-13265D01*
X658939Y-13663D01*
X658541Y-14258D01*
X658401Y-14961D01*
X658541Y-15663D01*
X658939Y-16258D01*
X659534Y-16656D01*
X660236Y-16796D01*
X660939Y-16656D01*
X661534Y-16258D01*
X661932Y-15663D01*
X662072Y-14961D01*
X661932Y-14258D01*
X661534Y-13663D01*
X660939Y-13265D01*
X660236Y-13125D01*
D02*
G37*
G36*
X640640Y-15417D02*
X639666Y-15611D01*
X638840Y-16163D01*
X638288Y-16988D01*
X638095Y-17962D01*
X638288Y-18936D01*
X638840Y-19762D01*
X639666Y-20313D01*
X640640Y-20507D01*
X641614Y-20313D01*
X642439Y-19762D01*
X642991Y-18936D01*
X643185Y-17962D01*
X642991Y-16988D01*
X642439Y-16163D01*
X641614Y-15611D01*
X640640Y-15417D01*
D02*
G37*
G36*
X658465Y-20064D02*
X657762Y-20204D01*
X657167Y-20602D01*
X656769Y-21197D01*
X656629Y-21899D01*
X656769Y-22602D01*
X657167Y-23197D01*
X657762Y-23595D01*
X658465Y-23734D01*
X659167Y-23595D01*
X659762Y-23197D01*
X660160Y-22602D01*
X660300Y-21899D01*
X660160Y-21197D01*
X659762Y-20602D01*
X659167Y-20204D01*
X658465Y-20064D01*
D02*
G37*
G36*
X625000D02*
X624298Y-20204D01*
X623702Y-20602D01*
X623304Y-21197D01*
X623165Y-21899D01*
X623304Y-22602D01*
X623702Y-23197D01*
X624298Y-23595D01*
X625000Y-23734D01*
X625702Y-23595D01*
X626298Y-23197D01*
X626696Y-22602D01*
X626835Y-21899D01*
X626696Y-21197D01*
X626298Y-20602D01*
X625702Y-20204D01*
X625000Y-20064D01*
D02*
G37*
G36*
X82785Y-19945D02*
X81811Y-20139D01*
X80986Y-20690D01*
X80434Y-21516D01*
X80240Y-22490D01*
X80434Y-23464D01*
X80986Y-24289D01*
X81811Y-24841D01*
X82785Y-25035D01*
X83759Y-24841D01*
X84585Y-24289D01*
X85137Y-23464D01*
X85330Y-22490D01*
X85137Y-21516D01*
X84585Y-20690D01*
X83759Y-20139D01*
X82785Y-19945D01*
D02*
G37*
G36*
X658465Y-27938D02*
X657762Y-28078D01*
X657167Y-28475D01*
X656769Y-29071D01*
X656629Y-29773D01*
X656769Y-30476D01*
X657167Y-31071D01*
X657762Y-31469D01*
X658465Y-31609D01*
X659167Y-31469D01*
X659762Y-31071D01*
X660160Y-30476D01*
X660300Y-29773D01*
X660160Y-29071D01*
X659762Y-28475D01*
X659167Y-28078D01*
X658465Y-27938D01*
D02*
G37*
G36*
X625000D02*
X624298Y-28078D01*
X623702Y-28475D01*
X623304Y-29071D01*
X623165Y-29773D01*
X623304Y-30476D01*
X623702Y-31071D01*
X624298Y-31469D01*
X625000Y-31609D01*
X625702Y-31469D01*
X626298Y-31071D01*
X626696Y-30476D01*
X626835Y-29773D01*
X626696Y-29071D01*
X626298Y-28475D01*
X625702Y-28078D01*
X625000Y-27938D01*
D02*
G37*
G36*
X640640Y-31165D02*
X639666Y-31359D01*
X638840Y-31911D01*
X638288Y-32736D01*
X638095Y-33710D01*
X638288Y-34684D01*
X638840Y-35510D01*
X639666Y-36061D01*
X640640Y-36255D01*
X641614Y-36061D01*
X642439Y-35510D01*
X642991Y-34684D01*
X643185Y-33710D01*
X642991Y-32736D01*
X642439Y-31911D01*
X641614Y-31359D01*
X640640Y-31165D01*
D02*
G37*
G36*
X679517Y-35188D02*
X678815Y-35327D01*
X678220Y-35725D01*
X677822Y-36321D01*
X677682Y-37023D01*
X677822Y-37725D01*
X678220Y-38321D01*
X678815Y-38718D01*
X679517Y-38858D01*
X680220Y-38718D01*
X680815Y-38321D01*
X681213Y-37725D01*
X681353Y-37023D01*
X681213Y-36321D01*
X680815Y-35725D01*
X680220Y-35327D01*
X679517Y-35188D01*
D02*
G37*
G36*
X658465Y-35812D02*
X657762Y-35952D01*
X657167Y-36349D01*
X656769Y-36945D01*
X656629Y-37647D01*
X656769Y-38350D01*
X657167Y-38945D01*
X657762Y-39343D01*
X658465Y-39483D01*
X659167Y-39343D01*
X659762Y-38945D01*
X660160Y-38350D01*
X660300Y-37647D01*
X660160Y-36945D01*
X659762Y-36349D01*
X659167Y-35952D01*
X658465Y-35812D01*
D02*
G37*
G36*
X101575Y-40291D02*
X100873Y-40430D01*
X100277Y-40828D01*
X99879Y-41424D01*
X99739Y-42126D01*
X99879Y-42828D01*
X100277Y-43424D01*
X100873Y-43821D01*
X101575Y-43961D01*
X102277Y-43821D01*
X102873Y-43424D01*
X103270Y-42828D01*
X103410Y-42126D01*
X103270Y-41424D01*
X102873Y-40828D01*
X102277Y-40430D01*
X101575Y-40291D01*
D02*
G37*
G36*
X675591Y-40684D02*
X674888Y-40824D01*
X674293Y-41222D01*
X673895Y-41817D01*
X673755Y-42520D01*
X673895Y-43222D01*
X674293Y-43817D01*
X674888Y-44215D01*
X675591Y-44355D01*
X676293Y-44215D01*
X676888Y-43817D01*
X677286Y-43222D01*
X677426Y-42520D01*
X677286Y-41817D01*
X676888Y-41222D01*
X676293Y-40824D01*
X675591Y-40684D01*
D02*
G37*
G36*
X64173D02*
X63471Y-40824D01*
X62875Y-41222D01*
X62478Y-41817D01*
X62338Y-42520D01*
X62478Y-43222D01*
X62875Y-43817D01*
X63471Y-44215D01*
X64173Y-44355D01*
X64876Y-44215D01*
X65471Y-43817D01*
X65869Y-43222D01*
X66009Y-42520D01*
X65869Y-41817D01*
X65471Y-41222D01*
X64876Y-40824D01*
X64173Y-40684D01*
D02*
G37*
G36*
X686319Y-41718D02*
X685617Y-41858D01*
X685021Y-42255D01*
X684623Y-42851D01*
X684484Y-43553D01*
X684623Y-44256D01*
X685021Y-44851D01*
X685617Y-45249D01*
X686319Y-45388D01*
X687021Y-45249D01*
X687617Y-44851D01*
X688015Y-44256D01*
X688154Y-43553D01*
X688015Y-42851D01*
X687617Y-42255D01*
X687021Y-41858D01*
X686319Y-41718D01*
D02*
G37*
G36*
X614567Y-43047D02*
X613865Y-43186D01*
X613269Y-43584D01*
X612871Y-44180D01*
X612732Y-44882D01*
X612871Y-45584D01*
X613269Y-46180D01*
X613865Y-46577D01*
X614567Y-46717D01*
X615269Y-46577D01*
X615865Y-46180D01*
X616262Y-45584D01*
X616402Y-44882D01*
X616262Y-44180D01*
X615865Y-43584D01*
X615269Y-43186D01*
X614567Y-43047D01*
D02*
G37*
G36*
X625000Y-46245D02*
X624298Y-46385D01*
X623702Y-46783D01*
X623304Y-47378D01*
X623165Y-48080D01*
X623304Y-48783D01*
X623702Y-49378D01*
X624298Y-49776D01*
X625000Y-49916D01*
X625702Y-49776D01*
X626298Y-49378D01*
X626696Y-48783D01*
X626835Y-48080D01*
X626696Y-47378D01*
X626298Y-46783D01*
X625702Y-46385D01*
X625000Y-46245D01*
D02*
G37*
G36*
X659449Y-47377D02*
X658746Y-47517D01*
X658151Y-47915D01*
X657753Y-48510D01*
X657614Y-49213D01*
X657753Y-49915D01*
X658151Y-50510D01*
X658746Y-50908D01*
X659449Y-51048D01*
X660151Y-50908D01*
X660746Y-50510D01*
X661144Y-49915D01*
X661284Y-49213D01*
X661144Y-48510D01*
X660746Y-47915D01*
X660151Y-47517D01*
X659449Y-47377D01*
D02*
G37*
G36*
X65945Y-48214D02*
X65243Y-48353D01*
X64647Y-48751D01*
X64249Y-49347D01*
X64110Y-50049D01*
X64249Y-50751D01*
X64647Y-51347D01*
X65243Y-51744D01*
X65945Y-51884D01*
X66647Y-51744D01*
X67243Y-51347D01*
X67641Y-50751D01*
X67780Y-50049D01*
X67641Y-49347D01*
X67243Y-48751D01*
X66647Y-48353D01*
X65945Y-48214D01*
D02*
G37*
G36*
X696577Y-49617D02*
X695875Y-49757D01*
X695280Y-50155D01*
X694882Y-50750D01*
X694742Y-51453D01*
X694882Y-52155D01*
X695280Y-52750D01*
X695875Y-53148D01*
X696577Y-53288D01*
X697280Y-53148D01*
X697875Y-52750D01*
X698273Y-52155D01*
X698413Y-51453D01*
X698273Y-50750D01*
X697875Y-50155D01*
X697280Y-49757D01*
X696577Y-49617D01*
D02*
G37*
G36*
X676772Y-49740D02*
X676069Y-49879D01*
X675474Y-50277D01*
X675076Y-50872D01*
X674936Y-51575D01*
X675076Y-52277D01*
X675474Y-52873D01*
Y-53033D01*
X675076Y-53628D01*
X674936Y-54331D01*
X675076Y-55033D01*
X675474Y-55628D01*
X676069Y-56026D01*
X676772Y-56166D01*
X677474Y-56026D01*
X678069Y-55628D01*
X678467Y-55033D01*
X678607Y-54331D01*
X678467Y-53628D01*
X678069Y-53033D01*
Y-52873D01*
X678467Y-52277D01*
X678607Y-51575D01*
X678467Y-50872D01*
X678069Y-50277D01*
X677474Y-49879D01*
X676772Y-49740D01*
D02*
G37*
G36*
X82785Y-51441D02*
X81811Y-51635D01*
X80986Y-52186D01*
X80434Y-53012D01*
X80240Y-53986D01*
X80434Y-54960D01*
X80986Y-55785D01*
X81811Y-56337D01*
X82785Y-56531D01*
X83759Y-56337D01*
X84585Y-55785D01*
X85137Y-54960D01*
X85330Y-53986D01*
X85137Y-53012D01*
X84585Y-52186D01*
X83759Y-51635D01*
X82785Y-51441D01*
D02*
G37*
G36*
X623228Y-53283D02*
X622526Y-53423D01*
X621931Y-53820D01*
X621533Y-54416D01*
X621393Y-55118D01*
X621533Y-55820D01*
X621931Y-56416D01*
X622526Y-56814D01*
X623228Y-56953D01*
X623931Y-56814D01*
X624526Y-56416D01*
X624924Y-55820D01*
X625064Y-55118D01*
X624924Y-54416D01*
X624526Y-53820D01*
X623931Y-53423D01*
X623228Y-53283D01*
D02*
G37*
G36*
X658114Y-54879D02*
X657412Y-55019D01*
X656816Y-55417D01*
X656419Y-56012D01*
X656279Y-56714D01*
X656419Y-57417D01*
X656816Y-58012D01*
X657412Y-58410D01*
X658114Y-58550D01*
X658816Y-58410D01*
X659412Y-58012D01*
X659810Y-57417D01*
X659949Y-56714D01*
X659810Y-56012D01*
X659412Y-55417D01*
X658816Y-55019D01*
X658114Y-54879D01*
D02*
G37*
G36*
X99410Y-56088D02*
X98707Y-56227D01*
X98112Y-56625D01*
X97714Y-57221D01*
X97574Y-57923D01*
X97714Y-58625D01*
X98112Y-59221D01*
X98707Y-59618D01*
X99410Y-59758D01*
X100112Y-59618D01*
X100707Y-59221D01*
X101105Y-58625D01*
X101245Y-57923D01*
X101105Y-57221D01*
X100707Y-56625D01*
X100112Y-56227D01*
X99410Y-56088D01*
D02*
G37*
G36*
X65945D02*
X65243Y-56227D01*
X64647Y-56625D01*
X64249Y-57221D01*
X64110Y-57923D01*
X64249Y-58625D01*
X64647Y-59221D01*
X65243Y-59618D01*
X65945Y-59758D01*
X66647Y-59618D01*
X67243Y-59221D01*
X67641Y-58625D01*
X67780Y-57923D01*
X67641Y-57221D01*
X67243Y-56625D01*
X66647Y-56227D01*
X65945Y-56088D01*
D02*
G37*
G36*
X623511Y-60717D02*
X622808Y-60857D01*
X622213Y-61255D01*
X621815Y-61850D01*
X621675Y-62552D01*
X621815Y-63255D01*
X622213Y-63850D01*
X622808Y-64248D01*
X623511Y-64388D01*
X624213Y-64248D01*
X624808Y-63850D01*
X625206Y-63255D01*
X625346Y-62552D01*
X625206Y-61850D01*
X624808Y-61255D01*
X624213Y-60857D01*
X623511Y-60717D01*
D02*
G37*
G36*
X657445Y-61690D02*
X656743Y-61830D01*
X656147Y-62228D01*
X655750Y-62823D01*
X655610Y-63525D01*
X655750Y-64228D01*
X656147Y-64823D01*
X656743Y-65221D01*
X657445Y-65361D01*
X658147Y-65221D01*
X658743Y-64823D01*
X659141Y-64228D01*
X659280Y-63525D01*
X659141Y-62823D01*
X658743Y-62228D01*
X658147Y-61830D01*
X657445Y-61690D01*
D02*
G37*
G36*
X99410Y-63962D02*
X98707Y-64101D01*
X98112Y-64499D01*
X97714Y-65095D01*
X97574Y-65797D01*
X97714Y-66499D01*
X98112Y-67095D01*
X98707Y-67492D01*
X99410Y-67632D01*
X100112Y-67492D01*
X100707Y-67095D01*
X101105Y-66499D01*
X101245Y-65797D01*
X101105Y-65095D01*
X100707Y-64499D01*
X100112Y-64101D01*
X99410Y-63962D01*
D02*
G37*
G36*
X65945D02*
X65243Y-64101D01*
X64647Y-64499D01*
X64249Y-65095D01*
X64110Y-65797D01*
X64249Y-66499D01*
X64647Y-67095D01*
X65243Y-67492D01*
X65945Y-67632D01*
X66647Y-67492D01*
X67243Y-67095D01*
X67641Y-66499D01*
X67780Y-65797D01*
X67641Y-65095D01*
X67243Y-64499D01*
X66647Y-64101D01*
X65945Y-63962D01*
D02*
G37*
G36*
X640640Y-62661D02*
X639666Y-62855D01*
X638840Y-63407D01*
X638288Y-64232D01*
X638095Y-65206D01*
X638288Y-66180D01*
X638840Y-67006D01*
X639666Y-67558D01*
X640640Y-67751D01*
X641614Y-67558D01*
X642439Y-67006D01*
X642991Y-66180D01*
X643185Y-65206D01*
X642991Y-64232D01*
X642439Y-63407D01*
X641614Y-62855D01*
X640640Y-62661D01*
D02*
G37*
G36*
X689466Y-64330D02*
X688764Y-64470D01*
X688168Y-64868D01*
X687771Y-65463D01*
X687631Y-66165D01*
X687771Y-66868D01*
X688168Y-67463D01*
X688764Y-67861D01*
X689466Y-68001D01*
X690168Y-67861D01*
X690764Y-67463D01*
X691162Y-66868D01*
X691301Y-66165D01*
X691162Y-65463D01*
X690764Y-64868D01*
X690168Y-64470D01*
X689466Y-64330D01*
D02*
G37*
G36*
X680082Y-62348D02*
X679380Y-62488D01*
X678784Y-62886D01*
X678386Y-63481D01*
X678247Y-64183D01*
X678386Y-64886D01*
X678784Y-65481D01*
X679380Y-65879D01*
X680082Y-66019D01*
X680784Y-65879D01*
X680857Y-65830D01*
X681307Y-66131D01*
X681292Y-66209D01*
X681431Y-66911D01*
X681829Y-67507D01*
X682425Y-67905D01*
X683127Y-68044D01*
X683829Y-67905D01*
X684425Y-67507D01*
X684823Y-66911D01*
X684962Y-66209D01*
X684823Y-65507D01*
X684425Y-64911D01*
X683829Y-64513D01*
X683127Y-64374D01*
X682425Y-64513D01*
X682352Y-64562D01*
X681902Y-64262D01*
X681917Y-64183D01*
X681777Y-63481D01*
X681380Y-62886D01*
X680784Y-62488D01*
X680082Y-62348D01*
D02*
G37*
G36*
X574016Y-68637D02*
X573313Y-68777D01*
X572718Y-69175D01*
X572691Y-69215D01*
X572191D01*
X572164Y-69175D01*
X571568Y-68777D01*
X570866Y-68637D01*
X570164Y-68777D01*
X569568Y-69175D01*
X569171Y-69770D01*
X569031Y-70472D01*
X569171Y-71175D01*
X569359Y-71457D01*
X569171Y-71739D01*
X569031Y-72441D01*
X569171Y-73143D01*
X569359Y-73425D01*
X569171Y-73707D01*
X569031Y-74410D01*
X569171Y-75112D01*
X569568Y-75707D01*
X570164Y-76105D01*
X570866Y-76245D01*
X571568Y-76105D01*
X572164Y-75707D01*
X572191Y-75667D01*
X572691D01*
X572718Y-75707D01*
X573313Y-76105D01*
X574016Y-76245D01*
X574718Y-76105D01*
X575314Y-75707D01*
X575711Y-75112D01*
X575851Y-74410D01*
X575711Y-73707D01*
X575523Y-73425D01*
X575711Y-73143D01*
X575851Y-72441D01*
X575711Y-71739D01*
X575523Y-71457D01*
X575711Y-71175D01*
X575851Y-70472D01*
X575711Y-69770D01*
X575314Y-69175D01*
X574718Y-68777D01*
X574016Y-68637D01*
D02*
G37*
G36*
X82785Y-67189D02*
X81811Y-67383D01*
X80986Y-67934D01*
X80434Y-68760D01*
X80240Y-69734D01*
X80434Y-70708D01*
X80986Y-71533D01*
X81811Y-72085D01*
X82785Y-72279D01*
X83759Y-72085D01*
X84585Y-71533D01*
X85137Y-70708D01*
X85330Y-69734D01*
X85137Y-68760D01*
X84585Y-67934D01*
X83759Y-67383D01*
X82785Y-67189D01*
D02*
G37*
G36*
X-23622Y-58204D02*
X-24324Y-58344D01*
X-24920Y-58742D01*
X-25318Y-59337D01*
X-25457Y-60039D01*
X-25318Y-60742D01*
X-25032Y-61168D01*
X-24958Y-61516D01*
X-25032Y-61863D01*
X-25318Y-62290D01*
X-25457Y-62992D01*
X-25318Y-63694D01*
X-24920Y-64290D01*
X-24324Y-64688D01*
X-24234Y-64706D01*
Y-65215D01*
X-24324Y-65234D01*
X-24920Y-65631D01*
X-25318Y-66227D01*
X-25457Y-66929D01*
X-25318Y-67631D01*
X-24920Y-68227D01*
X-24324Y-68625D01*
X-24234Y-68643D01*
Y-69152D01*
X-24324Y-69171D01*
X-24920Y-69568D01*
X-25318Y-70164D01*
X-25457Y-70866D01*
X-25318Y-71569D01*
X-24920Y-72164D01*
X-24324Y-72562D01*
X-23622Y-72701D01*
X-22920Y-72562D01*
X-22324Y-72164D01*
X-21926Y-71569D01*
X-21787Y-70866D01*
X-21926Y-70164D01*
X-22324Y-69568D01*
X-22920Y-69171D01*
X-23010Y-69152D01*
Y-68643D01*
X-22920Y-68625D01*
X-22324Y-68227D01*
X-21926Y-67631D01*
X-21787Y-66929D01*
X-21926Y-66227D01*
X-22324Y-65631D01*
X-22920Y-65234D01*
X-23010Y-65215D01*
Y-64706D01*
X-22920Y-64688D01*
X-22324Y-64290D01*
X-21926Y-63694D01*
X-21787Y-62992D01*
X-21926Y-62290D01*
X-22212Y-61863D01*
X-22286Y-61516D01*
X-22212Y-61168D01*
X-21926Y-60742D01*
X-21787Y-60039D01*
X-21926Y-59337D01*
X-22324Y-58742D01*
X-22920Y-58344D01*
X-23622Y-58204D01*
D02*
G37*
G36*
X670538Y-72574D02*
X669836Y-72714D01*
X669488Y-72946D01*
X669140Y-72714D01*
X668438Y-72574D01*
X667736Y-72714D01*
X667140Y-73112D01*
X666743Y-73707D01*
X666603Y-74409D01*
X666743Y-75112D01*
X667140Y-75707D01*
X667736Y-76105D01*
X668438Y-76245D01*
X669140Y-76105D01*
X669488Y-75873D01*
X669836Y-76105D01*
X670538Y-76245D01*
X671241Y-76105D01*
X671836Y-75707D01*
X672234Y-75112D01*
X672373Y-74409D01*
X672234Y-73707D01*
X671836Y-73112D01*
X671241Y-72714D01*
X670538Y-72574D01*
D02*
G37*
G36*
X658053Y-69353D02*
X657351Y-69493D01*
X656756Y-69890D01*
X656358Y-70486D01*
X656218Y-71188D01*
X656358Y-71890D01*
X656756Y-72486D01*
X657351Y-72884D01*
X658053Y-73023D01*
X658756Y-72884D01*
X659351Y-72486D01*
X659749Y-71890D01*
X659889Y-71188D01*
X659749Y-70486D01*
X659351Y-69890D01*
X658756Y-69493D01*
X658053Y-69353D01*
D02*
G37*
G36*
X131890Y-70851D02*
X131187Y-70991D01*
X130592Y-71389D01*
X130194Y-71984D01*
X130054Y-72687D01*
X130194Y-73389D01*
X130592Y-73984D01*
X131187Y-74382D01*
X131890Y-74522D01*
X132592Y-74382D01*
X133187Y-73984D01*
X133585Y-73389D01*
X133725Y-72687D01*
X133585Y-71984D01*
X133187Y-71389D01*
X132592Y-70991D01*
X131890Y-70851D01*
D02*
G37*
G36*
X597227Y-75268D02*
X596525Y-75407D01*
X595930Y-75805D01*
X595532Y-76401D01*
X595392Y-77103D01*
X595532Y-77805D01*
X595930Y-78401D01*
X596525Y-78799D01*
X597227Y-78938D01*
X597930Y-78799D01*
X598525Y-78401D01*
X598923Y-77805D01*
X599063Y-77103D01*
X598923Y-76401D01*
X598525Y-75805D01*
X597930Y-75407D01*
X597227Y-75268D01*
D02*
G37*
G36*
X618898Y-80448D02*
X618195Y-80588D01*
X617600Y-80986D01*
X617202Y-81581D01*
X617062Y-82284D01*
X617202Y-82986D01*
X617600Y-83581D01*
X618195Y-83979D01*
X618898Y-84119D01*
X619600Y-83979D01*
X620195Y-83581D01*
X620593Y-82986D01*
X620733Y-82284D01*
X620593Y-81581D01*
X620195Y-80986D01*
X619600Y-80588D01*
X618898Y-80448D01*
D02*
G37*
G36*
X599279Y-81146D02*
X598576Y-81285D01*
X597981Y-81683D01*
X597583Y-82278D01*
X597443Y-82981D01*
X597583Y-83683D01*
X597981Y-84278D01*
X598576Y-84676D01*
X599279Y-84816D01*
X599981Y-84676D01*
X600576Y-84278D01*
X600974Y-83683D01*
X601114Y-82981D01*
X600974Y-82278D01*
X600576Y-81683D01*
X599981Y-81285D01*
X599279Y-81146D01*
D02*
G37*
G36*
X578168Y-78943D02*
X577465Y-79083D01*
X576870Y-79480D01*
X576472Y-80076D01*
X576332Y-80778D01*
X576472Y-81480D01*
X576750Y-81896D01*
X576710Y-82524D01*
X576655Y-82561D01*
X576257Y-83156D01*
X576118Y-83858D01*
X576257Y-84561D01*
X576655Y-85156D01*
X577250Y-85554D01*
X577953Y-85694D01*
X578655Y-85554D01*
X579250Y-85156D01*
X579648Y-84561D01*
X579788Y-83858D01*
X579648Y-83156D01*
X579327Y-82675D01*
X579411Y-82112D01*
X579465Y-82076D01*
X579863Y-81480D01*
X580003Y-80778D01*
X579863Y-80076D01*
X579465Y-79480D01*
X578870Y-79083D01*
X578168Y-78943D01*
D02*
G37*
G36*
X612205Y-85173D02*
X611502Y-85312D01*
X610907Y-85710D01*
X610509Y-86306D01*
X610369Y-87008D01*
X610509Y-87710D01*
X610907Y-88306D01*
X611502Y-88703D01*
X612205Y-88843D01*
X612907Y-88703D01*
X613502Y-88306D01*
X613900Y-87710D01*
X614040Y-87008D01*
X613900Y-86306D01*
X613502Y-85710D01*
X612907Y-85312D01*
X612205Y-85173D01*
D02*
G37*
G36*
X568504Y-86354D02*
X567802Y-86493D01*
X567206Y-86891D01*
X566808Y-87487D01*
X566669Y-88189D01*
X566808Y-88891D01*
X567206Y-89487D01*
X567802Y-89885D01*
X568504Y-90024D01*
X569206Y-89885D01*
X569802Y-89487D01*
X570199Y-88891D01*
X570339Y-88189D01*
X570199Y-87487D01*
X569802Y-86891D01*
X569206Y-86493D01*
X568504Y-86354D01*
D02*
G37*
G36*
X366929Y-74149D02*
X366227Y-74289D01*
X365631Y-74686D01*
X365234Y-75282D01*
X365094Y-75984D01*
X365234Y-76687D01*
X365631Y-77282D01*
X365891Y-77455D01*
Y-78057D01*
X365631Y-78230D01*
X365234Y-78825D01*
X365094Y-79528D01*
X365234Y-80230D01*
X365631Y-80825D01*
X365891Y-80998D01*
Y-81600D01*
X365631Y-81773D01*
X365234Y-82369D01*
X365094Y-83071D01*
X365234Y-83773D01*
X365631Y-84369D01*
X365891Y-84542D01*
Y-85143D01*
X365631Y-85316D01*
X365234Y-85912D01*
X365094Y-86614D01*
X365234Y-87317D01*
X365631Y-87912D01*
Y-88072D01*
X365234Y-88668D01*
X365094Y-89370D01*
X365234Y-90072D01*
X365631Y-90668D01*
X366227Y-91066D01*
X366929Y-91205D01*
X367631Y-91066D01*
X368227Y-90668D01*
X368625Y-90072D01*
X368764Y-89370D01*
X368625Y-88668D01*
X368227Y-88072D01*
Y-87912D01*
X368625Y-87317D01*
X368764Y-86614D01*
X368625Y-85912D01*
X368227Y-85316D01*
X367968Y-85143D01*
Y-84542D01*
X368227Y-84369D01*
X368625Y-83773D01*
X368764Y-83071D01*
X368625Y-82369D01*
X368227Y-81773D01*
X367968Y-81600D01*
Y-80998D01*
X368227Y-80825D01*
X368625Y-80230D01*
X368764Y-79528D01*
X368625Y-78825D01*
X368227Y-78230D01*
X367968Y-78057D01*
Y-77455D01*
X368227Y-77282D01*
X368625Y-76687D01*
X368764Y-75984D01*
X368625Y-75282D01*
X368227Y-74686D01*
X367631Y-74289D01*
X366929Y-74149D01*
D02*
G37*
G36*
X104528Y-90339D02*
X103825Y-90479D01*
X103230Y-90877D01*
X102832Y-91473D01*
X102692Y-92175D01*
X102832Y-92877D01*
X103230Y-93472D01*
X103825Y-93870D01*
X104528Y-94010D01*
X105230Y-93870D01*
X105825Y-93472D01*
X106223Y-92877D01*
X106363Y-92175D01*
X106223Y-91473D01*
X105825Y-90877D01*
X105230Y-90479D01*
X104528Y-90339D01*
D02*
G37*
G36*
X623228Y-91472D02*
X622526Y-91611D01*
X621931Y-92009D01*
X621533Y-92605D01*
X621393Y-93307D01*
X621533Y-94009D01*
X621931Y-94605D01*
X622526Y-95003D01*
X623228Y-95142D01*
X623931Y-95003D01*
X624526Y-94605D01*
X624924Y-94009D01*
X625064Y-93307D01*
X624924Y-92605D01*
X624526Y-92009D01*
X623931Y-91611D01*
X623228Y-91472D01*
D02*
G37*
G36*
X592520D02*
X591817Y-91611D01*
X591222Y-92009D01*
X590824Y-92605D01*
X590684Y-93307D01*
X590824Y-94009D01*
X591222Y-94605D01*
X591817Y-95003D01*
X592520Y-95142D01*
X593222Y-95003D01*
X593817Y-94605D01*
X594215Y-94009D01*
X594355Y-93307D01*
X594215Y-92605D01*
X593817Y-92009D01*
X593222Y-91611D01*
X592520Y-91472D01*
D02*
G37*
G36*
X567323Y-92259D02*
X566620Y-92399D01*
X566025Y-92797D01*
X565627Y-93392D01*
X565488Y-94095D01*
X565627Y-94797D01*
X566025Y-95392D01*
X566620Y-95790D01*
X567323Y-95930D01*
X568025Y-95790D01*
X568621Y-95392D01*
X569018Y-94797D01*
X569158Y-94095D01*
X569018Y-93392D01*
X568621Y-92797D01*
X568025Y-92399D01*
X567323Y-92259D01*
D02*
G37*
G36*
X601745Y-96215D02*
X601042Y-96355D01*
X600447Y-96753D01*
X600049Y-97348D01*
X599909Y-98051D01*
X600049Y-98753D01*
X600447Y-99348D01*
X601042Y-99746D01*
X601745Y-99886D01*
X602447Y-99746D01*
X603042Y-99348D01*
X603440Y-98753D01*
X603580Y-98051D01*
X603440Y-97348D01*
X603042Y-96753D01*
X602447Y-96355D01*
X601745Y-96215D01*
D02*
G37*
G36*
X612598Y-98165D02*
X611896Y-98304D01*
X611301Y-98702D01*
X610903Y-99298D01*
X610763Y-100000D01*
X610903Y-100702D01*
X611301Y-101298D01*
X611896Y-101696D01*
X612598Y-101835D01*
X613301Y-101696D01*
X613896Y-101298D01*
X614294Y-100702D01*
X614434Y-100000D01*
X614294Y-99298D01*
X613896Y-98702D01*
X613301Y-98304D01*
X612598Y-98165D01*
D02*
G37*
G36*
X620959Y-98212D02*
X620257Y-98352D01*
X619661Y-98750D01*
X619263Y-99345D01*
X619124Y-100047D01*
X619263Y-100750D01*
X619661Y-101345D01*
X620257Y-101743D01*
X620959Y-101883D01*
X621661Y-101743D01*
X622257Y-101345D01*
X622654Y-100750D01*
X622794Y-100047D01*
X622654Y-99345D01*
X622257Y-98750D01*
X621661Y-98352D01*
X620959Y-98212D01*
D02*
G37*
G36*
X588372Y-99109D02*
X587670Y-99249D01*
X587075Y-99647D01*
X586677Y-100242D01*
X586537Y-100945D01*
X586677Y-101647D01*
X587075Y-102242D01*
X587670Y-102640D01*
X588372Y-102780D01*
X589075Y-102640D01*
X589670Y-102242D01*
X590068Y-101647D01*
X590207Y-100945D01*
X590068Y-100242D01*
X589670Y-99647D01*
X589075Y-99249D01*
X588372Y-99109D01*
D02*
G37*
G36*
X579921Y-100133D02*
X579219Y-100273D01*
X578623Y-100671D01*
X578226Y-101266D01*
X578086Y-101969D01*
X578226Y-102671D01*
X578623Y-103266D01*
X579219Y-103664D01*
X579921Y-103804D01*
X580624Y-103664D01*
X581219Y-103266D01*
X581617Y-102671D01*
X581756Y-101969D01*
X581617Y-101266D01*
X581219Y-100671D01*
X580624Y-100273D01*
X579921Y-100133D01*
D02*
G37*
G36*
X435827Y-101708D02*
X435124Y-101848D01*
X434529Y-102246D01*
X434131Y-102841D01*
X433991Y-103543D01*
X434131Y-104246D01*
X434529Y-104841D01*
X435124Y-105239D01*
X435827Y-105379D01*
X436529Y-105239D01*
X437124Y-104841D01*
X437522Y-104246D01*
X437662Y-103543D01*
X437522Y-102841D01*
X437124Y-102246D01*
X436529Y-101848D01*
X435827Y-101708D01*
D02*
G37*
G36*
X310069Y-83916D02*
X308343Y-84052D01*
X306659Y-84456D01*
X305060Y-85119D01*
X303583Y-86024D01*
X302267Y-87148D01*
X301142Y-88465D01*
X300238Y-89941D01*
X299575Y-91541D01*
X299171Y-93224D01*
X299035Y-94950D01*
X299171Y-96676D01*
X299575Y-98360D01*
X300238Y-99960D01*
X301142Y-101436D01*
X302267Y-102753D01*
X303583Y-103877D01*
X305060Y-104782D01*
X306659Y-105444D01*
X308343Y-105849D01*
X310069Y-105984D01*
X311795Y-105849D01*
X313479Y-105444D01*
X315078Y-104782D01*
X316555Y-103877D01*
X317871Y-102753D01*
X318996Y-101436D01*
X319900Y-99960D01*
X320563Y-98360D01*
X320967Y-96676D01*
X321103Y-94950D01*
X320967Y-93224D01*
X320563Y-91541D01*
X319900Y-89941D01*
X318996Y-88465D01*
X317871Y-87148D01*
X316555Y-86024D01*
X315078Y-85119D01*
X313479Y-84456D01*
X311795Y-84052D01*
X310069Y-83916D01*
D02*
G37*
G36*
X71880D02*
X70154Y-84052D01*
X68470Y-84456D01*
X66871Y-85119D01*
X65394Y-86024D01*
X64078Y-87148D01*
X62953Y-88465D01*
X62049Y-89941D01*
X61386Y-91541D01*
X60982Y-93224D01*
X60846Y-94950D01*
X60982Y-96676D01*
X61386Y-98360D01*
X62049Y-99960D01*
X62953Y-101436D01*
X64078Y-102753D01*
X65394Y-103877D01*
X66871Y-104782D01*
X68470Y-105444D01*
X70154Y-105849D01*
X71880Y-105984D01*
X73606Y-105849D01*
X75290Y-105444D01*
X76889Y-104782D01*
X78366Y-103877D01*
X79682Y-102753D01*
X80807Y-101436D01*
X81711Y-99960D01*
X82374Y-98360D01*
X82778Y-96676D01*
X82914Y-94950D01*
X82778Y-93224D01*
X82374Y-91541D01*
X81711Y-89941D01*
X80807Y-88465D01*
X79682Y-87148D01*
X78366Y-86024D01*
X76889Y-85119D01*
X75290Y-84456D01*
X73606Y-84052D01*
X71880Y-83916D01*
D02*
G37*
G36*
X512795Y-102379D02*
X512093Y-102519D01*
X511497Y-102917D01*
X511100Y-103512D01*
X510960Y-104214D01*
X511100Y-104917D01*
X511497Y-105512D01*
X512093Y-105910D01*
X512795Y-106049D01*
X513498Y-105910D01*
X514093Y-105512D01*
X514491Y-104917D01*
X514631Y-104214D01*
X514491Y-103512D01*
X514093Y-102917D01*
X513498Y-102519D01*
X512795Y-102379D01*
D02*
G37*
G36*
X651545Y-84074D02*
X649819Y-84210D01*
X648136Y-84614D01*
X646536Y-85276D01*
X645060Y-86181D01*
X643743Y-87306D01*
X642619Y-88622D01*
X641714Y-90099D01*
X641051Y-91698D01*
X640647Y-93382D01*
X640511Y-95108D01*
X640647Y-96834D01*
X641051Y-98518D01*
X641714Y-100117D01*
X642619Y-101593D01*
X643743Y-102910D01*
X645060Y-104034D01*
X646536Y-104939D01*
X648136Y-105602D01*
X649819Y-106006D01*
X651545Y-106142D01*
X653271Y-106006D01*
X654955Y-105602D01*
X656555Y-104939D01*
X658031Y-104034D01*
X659347Y-102910D01*
X660472Y-101593D01*
X661377Y-100117D01*
X662039Y-98518D01*
X662443Y-96834D01*
X662579Y-95108D01*
X662443Y-93382D01*
X662039Y-91698D01*
X661377Y-90099D01*
X660472Y-88622D01*
X659347Y-87306D01*
X658031Y-86181D01*
X656555Y-85276D01*
X654955Y-84614D01*
X653271Y-84210D01*
X651545Y-84074D01*
D02*
G37*
G36*
X413356D02*
X411630Y-84210D01*
X409947Y-84614D01*
X408347Y-85276D01*
X406871Y-86181D01*
X405554Y-87306D01*
X404430Y-88622D01*
X403525Y-90099D01*
X402862Y-91698D01*
X402458Y-93382D01*
X402322Y-95108D01*
X402458Y-96834D01*
X402862Y-98518D01*
X403525Y-100117D01*
X404430Y-101593D01*
X405554Y-102910D01*
X406871Y-104034D01*
X408347Y-104939D01*
X409947Y-105602D01*
X411630Y-106006D01*
X413356Y-106142D01*
X415082Y-106006D01*
X416766Y-105602D01*
X418366Y-104939D01*
X419842Y-104034D01*
X421159Y-102910D01*
X422283Y-101593D01*
X423188Y-100117D01*
X423850Y-98518D01*
X424254Y-96834D01*
X424390Y-95108D01*
X424254Y-93382D01*
X423850Y-91698D01*
X423188Y-90099D01*
X422283Y-88622D01*
X421159Y-87306D01*
X419842Y-86181D01*
X418366Y-85276D01*
X416766Y-84614D01*
X415082Y-84210D01*
X413356Y-84074D01*
D02*
G37*
G36*
X228824Y-103015D02*
X228121Y-103154D01*
X227526Y-103552D01*
X227128Y-104148D01*
X226989Y-104850D01*
X227128Y-105552D01*
X227526Y-106148D01*
X228121Y-106545D01*
X228824Y-106685D01*
X229526Y-106545D01*
X230121Y-106148D01*
X230519Y-105552D01*
X230659Y-104850D01*
X230519Y-104148D01*
X230121Y-103552D01*
X229526Y-103154D01*
X228824Y-103015D01*
D02*
G37*
G36*
X483484Y-104004D02*
X482782Y-104144D01*
X482186Y-104542D01*
X481788Y-105137D01*
X481649Y-105840D01*
X481788Y-106542D01*
X482186Y-107137D01*
X482782Y-107535D01*
X483484Y-107675D01*
X484186Y-107535D01*
X484782Y-107137D01*
X485180Y-106542D01*
X485319Y-105840D01*
X485180Y-105137D01*
X484782Y-104542D01*
X484186Y-104144D01*
X483484Y-104004D01*
D02*
G37*
G36*
X473228Y-104070D02*
X472526Y-104210D01*
X471931Y-104608D01*
X471533Y-105203D01*
X471393Y-105905D01*
X471533Y-106608D01*
X471931Y-107203D01*
X472526Y-107601D01*
X473228Y-107741D01*
X473931Y-107601D01*
X474526Y-107203D01*
X474924Y-106608D01*
X475064Y-105905D01*
X474924Y-105203D01*
X474526Y-104608D01*
X473931Y-104210D01*
X473228Y-104070D01*
D02*
G37*
G36*
X269685Y-104316D02*
X268983Y-104456D01*
X268387Y-104853D01*
X267989Y-105449D01*
X267850Y-106151D01*
X267989Y-106853D01*
X268387Y-107449D01*
X268983Y-107847D01*
X269685Y-107986D01*
X270387Y-107847D01*
X270983Y-107449D01*
X271381Y-106853D01*
X271520Y-106151D01*
X271381Y-105449D01*
X270983Y-104853D01*
X270387Y-104456D01*
X269685Y-104316D01*
D02*
G37*
G36*
X504703Y-104837D02*
X504001Y-104977D01*
X503406Y-105375D01*
X503008Y-105970D01*
X502868Y-106672D01*
X503008Y-107375D01*
X503406Y-107970D01*
X504001Y-108368D01*
X504703Y-108508D01*
X505406Y-108368D01*
X506001Y-107970D01*
X506399Y-107375D01*
X506539Y-106672D01*
X506399Y-105970D01*
X506001Y-105375D01*
X505406Y-104977D01*
X504703Y-104837D01*
D02*
G37*
G36*
X667717Y-104858D02*
X667014Y-104997D01*
X666419Y-105395D01*
X666021Y-105991D01*
X665881Y-106693D01*
X666021Y-107395D01*
X666419Y-107991D01*
X667014Y-108388D01*
X667717Y-108528D01*
X668419Y-108388D01*
X669014Y-107991D01*
X669412Y-107395D01*
X669552Y-106693D01*
X669412Y-105991D01*
X669014Y-105395D01*
X668419Y-104997D01*
X667717Y-104858D01*
D02*
G37*
G36*
X377165Y-105448D02*
X376463Y-105588D01*
X375868Y-105986D01*
X375470Y-106581D01*
X375330Y-107283D01*
X375470Y-107986D01*
X375868Y-108581D01*
X376463Y-108979D01*
X377165Y-109119D01*
X377868Y-108979D01*
X378430Y-108604D01*
X378577Y-108542D01*
X378990D01*
X379041Y-108618D01*
X379636Y-109016D01*
X380339Y-109156D01*
X381041Y-109016D01*
X381595Y-108646D01*
X382126Y-108717D01*
X382167Y-108778D01*
X382762Y-109176D01*
X383465Y-109316D01*
X384167Y-109176D01*
X384762Y-108778D01*
X385160Y-108183D01*
X385300Y-107480D01*
X385160Y-106778D01*
X384762Y-106183D01*
X384167Y-105785D01*
X383465Y-105645D01*
X382762Y-105785D01*
X382208Y-106155D01*
X381677Y-106084D01*
X381636Y-106023D01*
X381041Y-105625D01*
X380339Y-105485D01*
X379636Y-105625D01*
X379074Y-106001D01*
X378927Y-106063D01*
X378514D01*
X378463Y-105986D01*
X377868Y-105588D01*
X377165Y-105448D01*
D02*
G37*
G36*
X107346Y-108401D02*
X106644Y-108541D01*
X106049Y-108939D01*
X105651Y-109534D01*
X105511Y-110236D01*
X105040Y-110430D01*
X104644Y-110509D01*
X104049Y-110907D01*
X103651Y-111502D01*
X103570Y-111910D01*
X103060D01*
X102979Y-111502D01*
X102581Y-110907D01*
X101986Y-110509D01*
X101651Y-110442D01*
X101182Y-110236D01*
X101042Y-109534D01*
X100644Y-108939D01*
X100049Y-108541D01*
X99347Y-108401D01*
X98644Y-108541D01*
X98049Y-108939D01*
X97651Y-109534D01*
X97575Y-109918D01*
X97284Y-110370D01*
X96581Y-110509D01*
X95986Y-110907D01*
X95588Y-111502D01*
X95448Y-112205D01*
X95588Y-112907D01*
X95986Y-113502D01*
X96581Y-113900D01*
X97284Y-114040D01*
X97986Y-113900D01*
X98581Y-113502D01*
X98979Y-112907D01*
X99029Y-112658D01*
X99538D01*
X99588Y-112907D01*
X99986Y-113502D01*
X100581Y-113900D01*
X101284Y-114040D01*
X101986Y-113900D01*
X102581Y-113502D01*
X102979Y-112907D01*
X103060Y-112500D01*
X103570D01*
X103651Y-112907D01*
X104049Y-113502D01*
X104644Y-113900D01*
X105347Y-114040D01*
X106049Y-113900D01*
X106644Y-113502D01*
X107042Y-112907D01*
X107120Y-112515D01*
X107630D01*
X107714Y-112938D01*
X108112Y-113534D01*
X108707Y-113932D01*
X109409Y-114072D01*
X110112Y-113932D01*
X110707Y-113534D01*
X111105Y-112938D01*
X111245Y-112236D01*
X111105Y-111534D01*
X110707Y-110939D01*
X110112Y-110541D01*
X109649Y-110449D01*
X109182Y-110236D01*
X109042Y-109534D01*
X108644Y-108939D01*
X108049Y-108541D01*
X107346Y-108401D01*
D02*
G37*
G36*
X354724Y-111944D02*
X354022Y-112084D01*
X353740Y-112272D01*
X353458Y-112084D01*
X352756Y-111944D01*
X352054Y-112084D01*
X351772Y-112272D01*
X351490Y-112084D01*
X350787Y-111944D01*
X350085Y-112084D01*
X349490Y-112482D01*
X349092Y-113077D01*
X348952Y-113779D01*
X349092Y-114482D01*
X349490Y-115077D01*
X349530Y-115104D01*
Y-115604D01*
X349490Y-115631D01*
X349092Y-116227D01*
X348952Y-116929D01*
X349092Y-117631D01*
X349490Y-118227D01*
X350085Y-118625D01*
X350787Y-118764D01*
X351490Y-118625D01*
X351772Y-118436D01*
X352054Y-118625D01*
X352756Y-118764D01*
X353458Y-118625D01*
X353740Y-118436D01*
X354022Y-118625D01*
X354724Y-118764D01*
X355427Y-118625D01*
X356022Y-118227D01*
X356420Y-117631D01*
X356560Y-116929D01*
X356420Y-116227D01*
X356022Y-115631D01*
X355982Y-115604D01*
Y-115104D01*
X356022Y-115077D01*
X356420Y-114482D01*
X356560Y-113779D01*
X356420Y-113077D01*
X356022Y-112482D01*
X355427Y-112084D01*
X354724Y-111944D01*
D02*
G37*
G36*
X443307Y-109188D02*
X442605Y-109328D01*
X442009Y-109726D01*
X441611Y-110321D01*
X441472Y-111024D01*
X441611Y-111726D01*
X442009Y-112321D01*
X442605Y-112719D01*
X443307Y-112859D01*
X444009Y-112719D01*
X444605Y-112321D01*
X445003Y-111726D01*
X445142Y-111024D01*
X445003Y-110321D01*
X444605Y-109726D01*
X444009Y-109328D01*
X443307Y-109188D01*
D02*
G37*
G36*
X246063D02*
X245361Y-109328D01*
X244765Y-109726D01*
X244367Y-110321D01*
X244228Y-111024D01*
X244367Y-111726D01*
X244765Y-112321D01*
X245361Y-112719D01*
X246063Y-112859D01*
X246765Y-112719D01*
X247361Y-112321D01*
X247759Y-111726D01*
X247898Y-111024D01*
X247759Y-110321D01*
X247361Y-109726D01*
X246765Y-109328D01*
X246063Y-109188D01*
D02*
G37*
G36*
X253690Y-110125D02*
X252988Y-110264D01*
X252392Y-110662D01*
X251994Y-111258D01*
X251855Y-111960D01*
X251994Y-112662D01*
X252392Y-113258D01*
X252988Y-113655D01*
X253690Y-113795D01*
X254392Y-113655D01*
X254976Y-113266D01*
X255100Y-113195D01*
X255530D01*
X255599Y-113298D01*
X256194Y-113696D01*
X256897Y-113836D01*
X257599Y-113696D01*
X258195Y-113298D01*
X258592Y-112703D01*
X258732Y-112001D01*
X258592Y-111298D01*
X258195Y-110703D01*
X257599Y-110305D01*
X256897Y-110165D01*
X256194Y-110305D01*
X255599Y-110703D01*
X255557Y-110766D01*
X255057D01*
X254988Y-110662D01*
X254392Y-110264D01*
X253690Y-110125D01*
D02*
G37*
G36*
X402719Y-110498D02*
X402016Y-110638D01*
X401421Y-111036D01*
X401023Y-111631D01*
X400883Y-112334D01*
X401023Y-113036D01*
X401421Y-113631D01*
X402016Y-114029D01*
X402719Y-114169D01*
X403421Y-114029D01*
X404016Y-113631D01*
X404414Y-113036D01*
X404554Y-112334D01*
X404414Y-111631D01*
X404016Y-111036D01*
X403421Y-110638D01*
X402719Y-110498D01*
D02*
G37*
G36*
X62986Y-110968D02*
X62284Y-111107D01*
X61689Y-111505D01*
X61291Y-112101D01*
X61151Y-112803D01*
X61291Y-113505D01*
X61689Y-114101D01*
X62284Y-114498D01*
X62986Y-114638D01*
X63689Y-114498D01*
X64284Y-114101D01*
X64682Y-113505D01*
X64822Y-112803D01*
X64682Y-112101D01*
X64284Y-111505D01*
X63689Y-111107D01*
X62986Y-110968D01*
D02*
G37*
G36*
X472441Y-111944D02*
X471739Y-112084D01*
X471143Y-112482D01*
X470745Y-113077D01*
X470606Y-113779D01*
X470745Y-114482D01*
X471143Y-115077D01*
X471739Y-115475D01*
X472441Y-115615D01*
X473143Y-115475D01*
X473739Y-115077D01*
X474136Y-114482D01*
X474276Y-113779D01*
X474136Y-113077D01*
X473739Y-112482D01*
X473143Y-112084D01*
X472441Y-111944D01*
D02*
G37*
G36*
X309016Y-112151D02*
X308313Y-112290D01*
X307718Y-112688D01*
X307320Y-113284D01*
X307181Y-113986D01*
X307320Y-114688D01*
X307718Y-115284D01*
X308313Y-115681D01*
X309016Y-115821D01*
X309718Y-115681D01*
X310314Y-115284D01*
X310711Y-114688D01*
X310851Y-113986D01*
X310711Y-113284D01*
X310314Y-112688D01*
X309718Y-112290D01*
X309016Y-112151D01*
D02*
G37*
G36*
X-23622Y-100527D02*
X-24324Y-100667D01*
X-24920Y-101065D01*
X-25318Y-101660D01*
X-25457Y-102362D01*
X-25318Y-103065D01*
X-24920Y-103660D01*
X-24324Y-104058D01*
X-24234Y-104076D01*
Y-104586D01*
X-24324Y-104604D01*
X-24920Y-105001D01*
X-25318Y-105597D01*
X-25457Y-106299D01*
X-25318Y-107001D01*
X-24920Y-107597D01*
X-24324Y-107995D01*
X-24234Y-108013D01*
Y-108523D01*
X-24324Y-108541D01*
X-24920Y-108939D01*
X-25318Y-109534D01*
X-25457Y-110236D01*
X-25318Y-110939D01*
X-24920Y-111534D01*
X-24324Y-111932D01*
X-24234Y-111950D01*
Y-112460D01*
X-24324Y-112478D01*
X-24920Y-112875D01*
X-25318Y-113471D01*
X-25457Y-114173D01*
X-25318Y-114875D01*
X-24920Y-115471D01*
X-24324Y-115869D01*
X-23622Y-116008D01*
X-22920Y-115869D01*
X-22324Y-115471D01*
X-21926Y-114875D01*
X-21787Y-114173D01*
X-21926Y-113471D01*
X-22324Y-112875D01*
X-22920Y-112478D01*
X-23010Y-112460D01*
Y-111950D01*
X-22920Y-111932D01*
X-22324Y-111534D01*
X-21926Y-110939D01*
X-21787Y-110236D01*
X-21926Y-109534D01*
X-22324Y-108939D01*
X-22920Y-108541D01*
X-23010Y-108523D01*
Y-108013D01*
X-22920Y-107995D01*
X-22324Y-107597D01*
X-21926Y-107001D01*
X-21787Y-106299D01*
X-21926Y-105597D01*
X-22324Y-105001D01*
X-22920Y-104604D01*
X-23010Y-104586D01*
Y-104076D01*
X-22920Y-104058D01*
X-22324Y-103660D01*
X-21926Y-103065D01*
X-21787Y-102362D01*
X-21926Y-101660D01*
X-22324Y-101065D01*
X-22920Y-100667D01*
X-23622Y-100527D01*
D02*
G37*
G36*
X193898Y-113174D02*
X193195Y-113314D01*
X192600Y-113712D01*
X192202Y-114307D01*
X192062Y-115009D01*
X192202Y-115712D01*
X192600Y-116307D01*
X193195Y-116705D01*
X193898Y-116845D01*
X194600Y-116705D01*
X195195Y-116307D01*
X195593Y-115712D01*
X195733Y-115009D01*
X195593Y-114307D01*
X195195Y-113712D01*
X194600Y-113314D01*
X193898Y-113174D01*
D02*
G37*
G36*
X538583Y-109976D02*
X537880Y-110116D01*
X537285Y-110513D01*
X536887Y-111109D01*
X536747Y-111811D01*
X536887Y-112513D01*
X537285Y-113109D01*
X537880Y-113507D01*
X538346Y-113599D01*
X538401Y-114120D01*
X537935Y-114431D01*
X537537Y-115027D01*
X537398Y-115729D01*
X537537Y-116431D01*
X537935Y-117027D01*
X538531Y-117425D01*
X539233Y-117564D01*
X539935Y-117425D01*
X540531Y-117027D01*
X540928Y-116431D01*
X541068Y-115729D01*
X540928Y-115027D01*
X540531Y-114431D01*
X539935Y-114033D01*
X539470Y-113941D01*
X539414Y-113420D01*
X539880Y-113109D01*
X540278Y-112513D01*
X540418Y-111811D01*
X540278Y-111109D01*
X539880Y-110513D01*
X539285Y-110116D01*
X538583Y-109976D01*
D02*
G37*
G36*
X463551Y-114190D02*
X462849Y-114330D01*
X462254Y-114727D01*
X461856Y-115323D01*
X461716Y-116025D01*
X461856Y-116727D01*
X462254Y-117323D01*
X462849Y-117721D01*
X463551Y-117860D01*
X464254Y-117721D01*
X464849Y-117323D01*
X465247Y-116727D01*
X465386Y-116025D01*
X465247Y-115323D01*
X464849Y-114727D01*
X464254Y-114330D01*
X463551Y-114190D01*
D02*
G37*
G36*
X456742Y-114208D02*
X456040Y-114347D01*
X455444Y-114745D01*
X455047Y-115341D01*
X454907Y-116043D01*
X455047Y-116745D01*
X455444Y-117341D01*
X456040Y-117738D01*
X456742Y-117878D01*
X457444Y-117738D01*
X458040Y-117341D01*
X458438Y-116745D01*
X458577Y-116043D01*
X458438Y-115341D01*
X458040Y-114745D01*
X457444Y-114347D01*
X456742Y-114208D01*
D02*
G37*
G36*
X238189Y-114306D02*
X237487Y-114446D01*
X236891Y-114844D01*
X236493Y-115439D01*
X236354Y-116142D01*
X236493Y-116844D01*
X236891Y-117439D01*
X237487Y-117837D01*
X238189Y-117977D01*
X238891Y-117837D01*
X239487Y-117439D01*
X239884Y-116844D01*
X240024Y-116142D01*
X239884Y-115439D01*
X239487Y-114844D01*
X238891Y-114446D01*
X238189Y-114306D01*
D02*
G37*
G36*
X508268Y-115488D02*
X507565Y-115627D01*
X506970Y-116025D01*
X506572Y-116621D01*
X506432Y-117323D01*
X506572Y-118025D01*
X506970Y-118621D01*
X507565Y-119018D01*
X508268Y-119158D01*
X508970Y-119018D01*
X509565Y-118621D01*
X509963Y-118025D01*
X510103Y-117323D01*
X509963Y-116621D01*
X509565Y-116025D01*
X508970Y-115627D01*
X508268Y-115488D01*
D02*
G37*
G36*
X533878Y-115881D02*
X533176Y-116021D01*
X532580Y-116418D01*
X532183Y-117014D01*
X532043Y-117716D01*
X532183Y-118419D01*
X532580Y-119014D01*
X533176Y-119412D01*
X533878Y-119551D01*
X534580Y-119412D01*
X535176Y-119014D01*
X535574Y-118419D01*
X535713Y-117716D01*
X535574Y-117014D01*
X535176Y-116418D01*
X534580Y-116021D01*
X533878Y-115881D01*
D02*
G37*
G36*
X255118Y-116669D02*
X254416Y-116808D01*
X253820Y-117206D01*
X253423Y-117802D01*
X253283Y-118504D01*
X253423Y-119206D01*
X253820Y-119802D01*
X254416Y-120200D01*
X255118Y-120339D01*
X255820Y-120200D01*
X256416Y-119802D01*
X256814Y-119206D01*
X256953Y-118504D01*
X256814Y-117802D01*
X256416Y-117206D01*
X255820Y-116808D01*
X255118Y-116669D01*
D02*
G37*
G36*
X314961Y-117111D02*
X314258Y-117251D01*
X313663Y-117649D01*
X313265Y-118244D01*
X313125Y-118947D01*
X313265Y-119649D01*
X313663Y-120244D01*
X314258Y-120642D01*
X314961Y-120782D01*
X315663Y-120642D01*
X316258Y-120244D01*
X316656Y-119649D01*
X316796Y-118947D01*
X316656Y-118244D01*
X316258Y-117649D01*
X315663Y-117251D01*
X314961Y-117111D01*
D02*
G37*
G36*
X193898Y-118095D02*
X193195Y-118235D01*
X192600Y-118633D01*
X192202Y-119228D01*
X192062Y-119931D01*
X192202Y-120633D01*
X192600Y-121228D01*
X193195Y-121626D01*
X193898Y-121766D01*
X194600Y-121626D01*
X195195Y-121228D01*
X195593Y-120633D01*
X195733Y-119931D01*
X195593Y-119228D01*
X195195Y-118633D01*
X194600Y-118235D01*
X193898Y-118095D01*
D02*
G37*
G36*
X70866Y-120212D02*
X70164Y-120352D01*
X69568Y-120749D01*
X69171Y-121345D01*
X69031Y-122047D01*
X69171Y-122750D01*
X69568Y-123345D01*
X70164Y-123743D01*
X70866Y-123882D01*
X71569Y-123743D01*
X72164Y-123345D01*
X72562Y-122750D01*
X72701Y-122047D01*
X72562Y-121345D01*
X72164Y-120749D01*
X71569Y-120352D01*
X70866Y-120212D01*
D02*
G37*
G36*
X185547Y-116028D02*
X177445D01*
Y-124130D01*
X185547D01*
Y-116028D01*
D02*
G37*
G36*
X161496Y-115993D02*
X160439Y-116132D01*
X159453Y-116540D01*
X158607Y-117189D01*
X157957Y-118036D01*
X157549Y-119021D01*
X157410Y-120079D01*
X157549Y-121136D01*
X157957Y-122122D01*
X158607Y-122968D01*
X159453Y-123617D01*
X160439Y-124026D01*
X161496Y-124165D01*
X162554Y-124026D01*
X163539Y-123617D01*
X164385Y-122968D01*
X165035Y-122122D01*
X165443Y-121136D01*
X165582Y-120079D01*
X165443Y-119021D01*
X165035Y-118036D01*
X164385Y-117189D01*
X163539Y-116540D01*
X162554Y-116132D01*
X161496Y-115993D01*
D02*
G37*
G36*
X151496D02*
X150438Y-116132D01*
X149453Y-116540D01*
X148607Y-117189D01*
X147957Y-118036D01*
X147549Y-119021D01*
X147410Y-120079D01*
X147549Y-121136D01*
X147957Y-122122D01*
X148607Y-122968D01*
X149453Y-123617D01*
X150438Y-124026D01*
X151496Y-124165D01*
X152554Y-124026D01*
X153539Y-123617D01*
X154385Y-122968D01*
X155035Y-122122D01*
X155443Y-121136D01*
X155582Y-120079D01*
X155443Y-119021D01*
X155035Y-118036D01*
X154385Y-117189D01*
X153539Y-116540D01*
X152554Y-116132D01*
X151496Y-115993D01*
D02*
G37*
G36*
X141496D02*
X140438Y-116132D01*
X139453Y-116540D01*
X138607Y-117189D01*
X137957Y-118036D01*
X137549Y-119021D01*
X137410Y-120079D01*
X137549Y-121136D01*
X137957Y-122122D01*
X138607Y-122968D01*
X139453Y-123617D01*
X140438Y-124026D01*
X141496Y-124165D01*
X142554Y-124026D01*
X143539Y-123617D01*
X144385Y-122968D01*
X145035Y-122122D01*
X145443Y-121136D01*
X145582Y-120079D01*
X145443Y-119021D01*
X145035Y-118036D01*
X144385Y-117189D01*
X143539Y-116540D01*
X142554Y-116132D01*
X141496Y-115993D01*
D02*
G37*
G36*
X271654Y-120999D02*
X270951Y-121139D01*
X270356Y-121537D01*
X269958Y-122132D01*
X269818Y-122835D01*
X269958Y-123537D01*
X270356Y-124132D01*
X270951Y-124530D01*
X271654Y-124670D01*
X272356Y-124530D01*
X272951Y-124132D01*
X273349Y-123537D01*
X273489Y-122835D01*
X273349Y-122132D01*
X272951Y-121537D01*
X272356Y-121139D01*
X271654Y-120999D01*
D02*
G37*
G36*
X505905Y-121787D02*
X505203Y-121926D01*
X504608Y-122324D01*
X504210Y-122920D01*
X504070Y-123622D01*
X504210Y-124324D01*
X504608Y-124920D01*
X505203Y-125318D01*
X505905Y-125457D01*
X506608Y-125318D01*
X507203Y-124920D01*
X507601Y-124324D01*
X507741Y-123622D01*
X507601Y-122920D01*
X507203Y-122324D01*
X506608Y-121926D01*
X505905Y-121787D01*
D02*
G37*
G36*
X309055Y-122032D02*
X308353Y-122172D01*
X307757Y-122570D01*
X307360Y-123165D01*
X307220Y-123868D01*
X307360Y-124570D01*
X307757Y-125165D01*
X308353Y-125563D01*
X309055Y-125703D01*
X309757Y-125563D01*
X310353Y-125165D01*
X310751Y-124570D01*
X310890Y-123868D01*
X310751Y-123165D01*
X310353Y-122570D01*
X309757Y-122172D01*
X309055Y-122032D01*
D02*
G37*
G36*
X254376Y-123911D02*
X253674Y-124051D01*
X253078Y-124449D01*
X252680Y-125044D01*
X252541Y-125747D01*
X252680Y-126449D01*
X253078Y-127044D01*
X253674Y-127442D01*
X254376Y-127582D01*
X255078Y-127442D01*
X255674Y-127044D01*
X256071Y-126449D01*
X256211Y-125747D01*
X256071Y-125044D01*
X255674Y-124449D01*
X255078Y-124051D01*
X254376Y-123911D01*
D02*
G37*
G36*
X241250Y-124412D02*
X240547Y-124551D01*
X239952Y-124949D01*
X239554Y-125545D01*
X239415Y-126247D01*
X239554Y-126949D01*
X239952Y-127545D01*
X240547Y-127942D01*
X241250Y-128082D01*
X241952Y-127942D01*
X242548Y-127545D01*
X242945Y-126949D01*
X243085Y-126247D01*
X242945Y-125545D01*
X242548Y-124949D01*
X241952Y-124551D01*
X241250Y-124412D01*
D02*
G37*
G36*
X475984Y-125330D02*
X475282Y-125470D01*
X474686Y-125868D01*
X474289Y-126463D01*
X474149Y-127165D01*
X474289Y-127868D01*
X474686Y-128463D01*
X475282Y-128861D01*
X475984Y-129001D01*
X476687Y-128861D01*
X477282Y-128463D01*
X477680Y-127868D01*
X477819Y-127165D01*
X477680Y-126463D01*
X477282Y-125868D01*
X476687Y-125470D01*
X475984Y-125330D01*
D02*
G37*
G36*
X375532Y-121774D02*
X374830Y-121914D01*
X374235Y-122312D01*
X373837Y-122907D01*
X373697Y-123610D01*
X373837Y-124312D01*
X374235Y-124908D01*
X374532Y-125106D01*
Y-125708D01*
X374293Y-125868D01*
X373895Y-126463D01*
X373755Y-127165D01*
X373895Y-127868D01*
X374293Y-128463D01*
X374888Y-128861D01*
X375590Y-129001D01*
X376293Y-128861D01*
X376888Y-128463D01*
X376915Y-128422D01*
X377328D01*
X377475Y-128485D01*
X378038Y-128861D01*
X378740Y-129001D01*
X379443Y-128861D01*
X379733Y-128667D01*
X380118Y-128498D01*
X380503Y-128667D01*
X380794Y-128861D01*
X381496Y-129001D01*
X382198Y-128861D01*
X382794Y-128463D01*
X383192Y-127868D01*
X383331Y-127165D01*
X383192Y-126463D01*
X382794Y-125868D01*
X382198Y-125470D01*
X381496Y-125330D01*
X380794Y-125470D01*
X380503Y-125664D01*
X380239Y-125780D01*
X379837Y-125552D01*
X379828Y-125060D01*
X380038Y-124920D01*
X380436Y-124324D01*
X380575Y-123622D01*
X380436Y-122920D01*
X380038Y-122324D01*
X379443Y-121926D01*
X378740Y-121787D01*
X378038Y-121926D01*
X377442Y-122324D01*
X377390Y-122402D01*
X376890D01*
X376830Y-122312D01*
X376235Y-121914D01*
X375532Y-121774D01*
D02*
G37*
G36*
X580315Y-128086D02*
X579613Y-128226D01*
X579017Y-128623D01*
X578619Y-129219D01*
X578601Y-129310D01*
X578092D01*
X578074Y-129219D01*
X577676Y-128623D01*
X577080Y-128226D01*
X576378Y-128086D01*
X575676Y-128226D01*
X575080Y-128623D01*
X574682Y-129219D01*
X574543Y-129921D01*
X574682Y-130624D01*
X575080Y-131219D01*
X575153Y-131267D01*
X574958Y-131738D01*
X574409Y-131629D01*
X573707Y-131769D01*
X573112Y-132167D01*
X573062Y-132241D01*
X572501Y-132260D01*
X572438Y-132182D01*
X572637Y-131639D01*
X572750Y-131617D01*
X573345Y-131219D01*
X573743Y-130624D01*
X573882Y-129921D01*
X573743Y-129219D01*
X573345Y-128623D01*
X572750Y-128226D01*
X572047Y-128086D01*
X571345Y-128226D01*
X570750Y-128623D01*
X570352Y-129219D01*
X570212Y-129921D01*
X570352Y-130624D01*
X570705Y-131152D01*
X570647Y-131469D01*
X570556Y-131691D01*
X570164Y-131769D01*
X569568Y-132167D01*
X569171Y-132762D01*
X569031Y-133465D01*
X569171Y-134167D01*
X569568Y-134762D01*
X570164Y-135160D01*
X570866Y-135300D01*
X571568Y-135160D01*
X572164Y-134762D01*
X572337Y-134503D01*
X572938D01*
X573112Y-134762D01*
X573707Y-135160D01*
X574409Y-135300D01*
X575112Y-135160D01*
X575707Y-134762D01*
X576105Y-134167D01*
X576245Y-133465D01*
X576105Y-132762D01*
X575707Y-132167D01*
X575635Y-132118D01*
X575830Y-131648D01*
X576378Y-131756D01*
X577080Y-131617D01*
X577676Y-131219D01*
X578074Y-130624D01*
X578092Y-130533D01*
X578601D01*
X578619Y-130624D01*
X579017Y-131219D01*
X579114Y-131284D01*
X579141Y-131410D01*
X579080Y-131862D01*
X578623Y-132167D01*
X578226Y-132762D01*
X578086Y-133465D01*
X578226Y-134167D01*
X578623Y-134762D01*
X579219Y-135160D01*
X579921Y-135300D01*
X580624Y-135160D01*
X581219Y-134762D01*
X581617Y-134167D01*
X581756Y-133465D01*
X581617Y-132762D01*
X581219Y-132167D01*
X581122Y-132102D01*
X581095Y-131976D01*
X581156Y-131524D01*
X581613Y-131219D01*
X582011Y-130624D01*
X582150Y-129921D01*
X582011Y-129219D01*
X581613Y-128623D01*
X581017Y-128226D01*
X580315Y-128086D01*
D02*
G37*
G36*
X309016Y-126824D02*
X308313Y-126963D01*
X307718Y-127361D01*
X307320Y-127957D01*
X307181Y-128659D01*
X307320Y-129361D01*
X307718Y-129957D01*
X308313Y-130355D01*
X309016Y-130494D01*
X309718Y-130355D01*
X310314Y-129957D01*
X310711Y-129361D01*
X310851Y-128659D01*
X310711Y-127957D01*
X310314Y-127361D01*
X309718Y-126963D01*
X309016Y-126824D01*
D02*
G37*
G36*
X524606Y-124001D02*
X523904Y-124141D01*
X523309Y-124539D01*
X522911Y-125134D01*
X522771Y-125836D01*
X522911Y-126539D01*
X523309Y-127134D01*
X523139Y-127622D01*
X522861Y-128037D01*
X522722Y-128740D01*
X522861Y-129442D01*
X523259Y-130037D01*
X523855Y-130435D01*
X524557Y-130575D01*
X525259Y-130435D01*
X525855Y-130037D01*
X526253Y-129442D01*
X526392Y-128740D01*
X526253Y-128037D01*
X525855Y-127442D01*
X526024Y-126954D01*
X526302Y-126539D01*
X526442Y-125836D01*
X526302Y-125134D01*
X525904Y-124539D01*
X525309Y-124141D01*
X524606Y-124001D01*
D02*
G37*
G36*
X144871Y-129774D02*
X144169Y-129914D01*
X143573Y-130312D01*
X143175Y-130907D01*
X143036Y-131609D01*
X143175Y-132312D01*
X143573Y-132907D01*
X144169Y-133305D01*
X144871Y-133444D01*
X145573Y-133305D01*
X146169Y-132907D01*
X146566Y-132312D01*
X146706Y-131609D01*
X146566Y-130907D01*
X146169Y-130312D01*
X145573Y-129914D01*
X144871Y-129774D01*
D02*
G37*
G36*
X117126Y-118086D02*
X116424Y-118226D01*
X115828Y-118623D01*
X115430Y-119219D01*
X115291Y-119921D01*
X115430Y-120624D01*
X115828Y-121219D01*
X116424Y-121617D01*
X116819Y-121695D01*
X116859Y-121727D01*
X116823Y-122263D01*
X116795Y-122277D01*
X116424Y-122351D01*
X115828Y-122749D01*
X115430Y-123344D01*
X115291Y-124047D01*
X115430Y-124749D01*
X115828Y-125344D01*
X116424Y-125742D01*
X116673Y-125792D01*
Y-126302D01*
X116424Y-126351D01*
X115828Y-126749D01*
X115430Y-127344D01*
X115291Y-128047D01*
X115430Y-128749D01*
X115828Y-129344D01*
X116424Y-129742D01*
X116674Y-129792D01*
Y-130302D01*
X116424Y-130352D01*
X115828Y-130749D01*
X115430Y-131345D01*
X115291Y-132047D01*
X115430Y-132750D01*
X115828Y-133345D01*
X116424Y-133743D01*
X117126Y-133882D01*
X117828Y-133743D01*
X118424Y-133345D01*
X118822Y-132750D01*
X118961Y-132047D01*
X119425Y-131816D01*
X119797Y-131742D01*
X120392Y-131344D01*
X120790Y-130749D01*
X120930Y-130047D01*
X120790Y-129344D01*
X120392Y-128749D01*
X119797Y-128351D01*
X119425Y-128277D01*
X118961Y-128047D01*
X118822Y-127344D01*
X118424Y-126749D01*
X117828Y-126351D01*
X117579Y-126302D01*
Y-125792D01*
X117828Y-125742D01*
X118424Y-125344D01*
X118822Y-124749D01*
X118961Y-124047D01*
X119425Y-123816D01*
X119797Y-123742D01*
X120392Y-123344D01*
X120790Y-122749D01*
X120930Y-122047D01*
X120790Y-121344D01*
X120392Y-120749D01*
X119797Y-120351D01*
X119401Y-120272D01*
X118961Y-119921D01*
X118822Y-119219D01*
X118424Y-118623D01*
X117828Y-118226D01*
X117126Y-118086D01*
D02*
G37*
G36*
X622001Y-121001D02*
X620744Y-121124D01*
X619535Y-121491D01*
X618421Y-122087D01*
X617444Y-122888D01*
X616643Y-123865D01*
X616047Y-124979D01*
X615680Y-126188D01*
X615556Y-127445D01*
X615680Y-128702D01*
X616047Y-129911D01*
X616643Y-131025D01*
X617444Y-132002D01*
X618421Y-132803D01*
X619535Y-133399D01*
X620744Y-133765D01*
X622001Y-133889D01*
X623258Y-133765D01*
X624467Y-133399D01*
X625581Y-132803D01*
X626558Y-132002D01*
X627359Y-131025D01*
X627955Y-129911D01*
X628321Y-128702D01*
X628445Y-127445D01*
X628321Y-126188D01*
X627955Y-124979D01*
X627359Y-123865D01*
X626558Y-122888D01*
X625581Y-122087D01*
X624467Y-121491D01*
X623258Y-121124D01*
X622001Y-121001D01*
D02*
G37*
G36*
X498032Y-130448D02*
X497329Y-130588D01*
X496734Y-130986D01*
X496336Y-131581D01*
X496196Y-132283D01*
X496336Y-132986D01*
X496734Y-133581D01*
X497329Y-133979D01*
X498032Y-134119D01*
X498734Y-133979D01*
X499329Y-133581D01*
X499727Y-132986D01*
X499867Y-132283D01*
X499727Y-131581D01*
X499329Y-130986D01*
X498734Y-130588D01*
X498032Y-130448D01*
D02*
G37*
G36*
X480120Y-130529D02*
X479417Y-130669D01*
X478822Y-131067D01*
X478424Y-131662D01*
X478284Y-132365D01*
X478424Y-133067D01*
X478822Y-133662D01*
X479417Y-134060D01*
X480120Y-134200D01*
X480822Y-134060D01*
X481417Y-133662D01*
X481815Y-133067D01*
X481955Y-132365D01*
X481815Y-131662D01*
X481417Y-131067D01*
X480822Y-130669D01*
X480120Y-130529D01*
D02*
G37*
G36*
X469685Y-131629D02*
X468983Y-131769D01*
X468387Y-132167D01*
X467989Y-132762D01*
X467850Y-133465D01*
X467989Y-134167D01*
X468387Y-134762D01*
X468983Y-135160D01*
X469685Y-135300D01*
X470387Y-135160D01*
X470983Y-134762D01*
X471381Y-134167D01*
X471520Y-133465D01*
X471381Y-132762D01*
X470983Y-132167D01*
X470387Y-131769D01*
X469685Y-131629D01*
D02*
G37*
G36*
X409900Y-134724D02*
X409198Y-134864D01*
X408602Y-135262D01*
X408204Y-135857D01*
X408065Y-136559D01*
X408204Y-137262D01*
X408602Y-137857D01*
X409198Y-138255D01*
X409900Y-138395D01*
X410602Y-138255D01*
X411198Y-137857D01*
X411595Y-137262D01*
X411735Y-136559D01*
X411595Y-135857D01*
X411198Y-135262D01*
X410602Y-134864D01*
X409900Y-134724D01*
D02*
G37*
G36*
X436614Y-134779D02*
X435912Y-134919D01*
X435316Y-135317D01*
X434919Y-135912D01*
X434779Y-136614D01*
X434919Y-137317D01*
X435316Y-137912D01*
X435912Y-138310D01*
X436614Y-138449D01*
X437317Y-138310D01*
X437912Y-137912D01*
X438310Y-137317D01*
X438449Y-136614D01*
X438310Y-135912D01*
X437912Y-135317D01*
X437317Y-134919D01*
X436614Y-134779D01*
D02*
G37*
G36*
X469521Y-135780D02*
X468818Y-135919D01*
X468223Y-136317D01*
X467825Y-136912D01*
X467685Y-137615D01*
X467825Y-138317D01*
X468223Y-138912D01*
X468818Y-139310D01*
X469521Y-139450D01*
X470223Y-139310D01*
X470818Y-138912D01*
X471216Y-138317D01*
X471356Y-137615D01*
X471216Y-136912D01*
X470818Y-136317D01*
X470223Y-135919D01*
X469521Y-135780D01*
D02*
G37*
G36*
X570472Y-135960D02*
X569770Y-136100D01*
X569175Y-136498D01*
X568777Y-137093D01*
X568637Y-137795D01*
X568777Y-138498D01*
X569175Y-139093D01*
X569770Y-139491D01*
X570472Y-139630D01*
X571175Y-139491D01*
X571770Y-139093D01*
X572168Y-138498D01*
X572308Y-137795D01*
X572168Y-137093D01*
X571770Y-136498D01*
X571175Y-136100D01*
X570472Y-135960D01*
D02*
G37*
G36*
X109409Y-138276D02*
X108707Y-138416D01*
X108112Y-138813D01*
X107714Y-139409D01*
X107664Y-139658D01*
X107155D01*
X107105Y-139409D01*
X106707Y-138813D01*
X106112Y-138416D01*
X105409Y-138276D01*
X104707Y-138416D01*
X104112Y-138813D01*
X103714Y-139409D01*
X103664Y-139658D01*
X103155D01*
X103105Y-139409D01*
X102707Y-138813D01*
X102112Y-138416D01*
X101409Y-138276D01*
X100707Y-138416D01*
X100112Y-138813D01*
X99714Y-139409D01*
X99664Y-139658D01*
X99155D01*
X99105Y-139409D01*
X98707Y-138813D01*
X98112Y-138416D01*
X97409Y-138276D01*
X96707Y-138416D01*
X96112Y-138813D01*
X95714Y-139409D01*
X95574Y-140111D01*
X95714Y-140813D01*
X96112Y-141409D01*
X96707Y-141807D01*
X97409Y-141946D01*
X97609Y-141907D01*
X97714Y-142435D01*
X98112Y-143030D01*
X98707Y-143428D01*
X99410Y-143568D01*
X100112Y-143428D01*
X100707Y-143030D01*
X101105Y-142435D01*
X101210Y-141907D01*
X101409Y-141946D01*
X102112Y-141807D01*
X102707Y-141409D01*
X103105Y-140813D01*
X103155Y-140564D01*
X103664D01*
X103714Y-140813D01*
X104112Y-141409D01*
X104707Y-141807D01*
X105409Y-141946D01*
X105609Y-141907D01*
X105714Y-142435D01*
X106112Y-143030D01*
X106707Y-143428D01*
X107409Y-143568D01*
X108112Y-143428D01*
X108707Y-143030D01*
X109105Y-142435D01*
X109210Y-141907D01*
X109409Y-141946D01*
X110112Y-141807D01*
X110707Y-141409D01*
X111105Y-140813D01*
X111245Y-140111D01*
X111105Y-139409D01*
X110707Y-138813D01*
X110112Y-138416D01*
X109409Y-138276D01*
D02*
G37*
G36*
X377559Y-133598D02*
X376857Y-133738D01*
X376261Y-134135D01*
X375864Y-134731D01*
X375724Y-135433D01*
X375864Y-136135D01*
X376261Y-136731D01*
X376857Y-137129D01*
X377409Y-137239D01*
X377299Y-137795D01*
X377438Y-138498D01*
X377836Y-139093D01*
X378432Y-139491D01*
X379134Y-139630D01*
X379681Y-139522D01*
X380009Y-139931D01*
X379801Y-140243D01*
X379661Y-140945D01*
X379704Y-141165D01*
X379733Y-141308D01*
X379255Y-141424D01*
X379172Y-141300D01*
X378857Y-140828D01*
X378261Y-140430D01*
X377559Y-140291D01*
X376857Y-140430D01*
X376261Y-140828D01*
X375864Y-141424D01*
X375724Y-142126D01*
X375864Y-142828D01*
X376261Y-143424D01*
X376857Y-143822D01*
X377559Y-143961D01*
X378261Y-143822D01*
X378857Y-143424D01*
X379255Y-142828D01*
X379394Y-142126D01*
X379351Y-141906D01*
X379322Y-141763D01*
X379801Y-141647D01*
X379883Y-141771D01*
X380198Y-142243D01*
X380794Y-142640D01*
X381496Y-142780D01*
X382198Y-142640D01*
X382794Y-142243D01*
X383192Y-141647D01*
X383331Y-140945D01*
X383192Y-140243D01*
X382794Y-139647D01*
X382697Y-139583D01*
X382670Y-139456D01*
X382731Y-139004D01*
X383188Y-138699D01*
X383585Y-138104D01*
X383725Y-137402D01*
X383585Y-136699D01*
X383188Y-136104D01*
X382592Y-135706D01*
X381890Y-135566D01*
X381187Y-135706D01*
X380592Y-136104D01*
X380361Y-136450D01*
X379836Y-136100D01*
X379284Y-135990D01*
X379394Y-135433D01*
X379255Y-134731D01*
X378857Y-134135D01*
X378261Y-133738D01*
X377559Y-133598D01*
D02*
G37*
G36*
X87254Y-137793D02*
X86552Y-137933D01*
X85957Y-138331D01*
X85559Y-138926D01*
X85419Y-139629D01*
X85559Y-140331D01*
X85957Y-140926D01*
X86552Y-141324D01*
X87254Y-141464D01*
X87957Y-141324D01*
X88060Y-141255D01*
X88269Y-141568D01*
X88865Y-141966D01*
X89567Y-142105D01*
X90269Y-141966D01*
X90865Y-141568D01*
X91263Y-140972D01*
X91402Y-140270D01*
X91263Y-139568D01*
X90865Y-138972D01*
X90269Y-138575D01*
X89567Y-138435D01*
X88865Y-138575D01*
X88761Y-138644D01*
X88552Y-138331D01*
X87957Y-137933D01*
X87254Y-137793D01*
D02*
G37*
G36*
X539900Y-138930D02*
X539198Y-139070D01*
X538602Y-139468D01*
X538205Y-140063D01*
X538065Y-140766D01*
X538205Y-141468D01*
X538602Y-142063D01*
X539198Y-142461D01*
X539900Y-142601D01*
X540602Y-142461D01*
X541198Y-142063D01*
X541596Y-141468D01*
X541736Y-140766D01*
X541596Y-140063D01*
X541198Y-139468D01*
X540602Y-139070D01*
X539900Y-138930D01*
D02*
G37*
G36*
X672401Y-128761D02*
X671048Y-128895D01*
X669747Y-129289D01*
X668549Y-129930D01*
X667498Y-130792D01*
X666636Y-131843D01*
X665995Y-133042D01*
X665601Y-134342D01*
X665467Y-135695D01*
X665601Y-137048D01*
X665995Y-138348D01*
X666636Y-139547D01*
X667498Y-140598D01*
X668549Y-141460D01*
X669747Y-142101D01*
X671048Y-142495D01*
X672401Y-142628D01*
X673753Y-142495D01*
X675054Y-142101D01*
X676253Y-141460D01*
X677303Y-140598D01*
X678166Y-139547D01*
X678806Y-138348D01*
X679201Y-137048D01*
X679334Y-135695D01*
X679201Y-134342D01*
X678806Y-133042D01*
X678166Y-131843D01*
X677303Y-130792D01*
X676253Y-129930D01*
X675054Y-129289D01*
X673753Y-128895D01*
X672401Y-128761D01*
D02*
G37*
G36*
X418898Y-142308D02*
X418195Y-142448D01*
X417863Y-142670D01*
X417531Y-142823D01*
X417107Y-142684D01*
X416808Y-142484D01*
X416106Y-142344D01*
X415403Y-142484D01*
X414808Y-142882D01*
X414410Y-143477D01*
X414270Y-144180D01*
X414410Y-144882D01*
X414808Y-145477D01*
X415403Y-145875D01*
X416106Y-146015D01*
X416808Y-145875D01*
X417140Y-145653D01*
X417472Y-145500D01*
X417896Y-145639D01*
X418195Y-145839D01*
X418898Y-145979D01*
X419600Y-145839D01*
X420195Y-145441D01*
X420593Y-144846D01*
X420733Y-144143D01*
X420593Y-143441D01*
X420195Y-142846D01*
X419600Y-142448D01*
X418898Y-142308D01*
D02*
G37*
G36*
X469291Y-142013D02*
X468589Y-142153D01*
X467994Y-142550D01*
X467596Y-143146D01*
X467456Y-143848D01*
X467596Y-144550D01*
X467994Y-145146D01*
X468589Y-145544D01*
X469291Y-145683D01*
X469994Y-145544D01*
X470589Y-145146D01*
X470987Y-144550D01*
X471127Y-143848D01*
X470987Y-143146D01*
X470589Y-142550D01*
X469994Y-142153D01*
X469291Y-142013D01*
D02*
G37*
G36*
X398568Y-143248D02*
X397866Y-143387D01*
X397270Y-143785D01*
X396873Y-144381D01*
X396733Y-145083D01*
X396873Y-145785D01*
X397270Y-146381D01*
X397866Y-146779D01*
X398568Y-146918D01*
X399271Y-146779D01*
X399866Y-146381D01*
X400264Y-145785D01*
X400403Y-145083D01*
X400264Y-144381D01*
X399866Y-143785D01*
X399271Y-143387D01*
X398568Y-143248D01*
D02*
G37*
G36*
X461319Y-141914D02*
X460617Y-142054D01*
X460021Y-142452D01*
X459623Y-143047D01*
X459484Y-143750D01*
X459623Y-144452D01*
X460021Y-145047D01*
X460617Y-145445D01*
X461319Y-145585D01*
X462021Y-145445D01*
X462341Y-145231D01*
X462701Y-145592D01*
X462633Y-145695D01*
X462493Y-146397D01*
X462633Y-147099D01*
X463031Y-147695D01*
X463626Y-148092D01*
X464328Y-148232D01*
X465031Y-148092D01*
X465626Y-147695D01*
X466024Y-147099D01*
X466164Y-146397D01*
X466024Y-145695D01*
X465626Y-145099D01*
X465031Y-144701D01*
X464328Y-144562D01*
X463626Y-144701D01*
X463306Y-144915D01*
X462946Y-144554D01*
X463015Y-144452D01*
X463154Y-143750D01*
X463015Y-143047D01*
X462617Y-142452D01*
X462021Y-142054D01*
X461319Y-141914D01*
D02*
G37*
G36*
X622001Y-137501D02*
X620744Y-137624D01*
X619535Y-137991D01*
X618421Y-138587D01*
X617444Y-139388D01*
X616643Y-140365D01*
X616047Y-141479D01*
X615680Y-142688D01*
X615556Y-143945D01*
X615680Y-145202D01*
X616047Y-146411D01*
X616643Y-147525D01*
X617444Y-148502D01*
X618421Y-149303D01*
X619535Y-149899D01*
X620744Y-150266D01*
X622001Y-150389D01*
X623258Y-150266D01*
X624467Y-149899D01*
X625581Y-149303D01*
X626558Y-148502D01*
X627359Y-147525D01*
X627955Y-146411D01*
X628321Y-145202D01*
X628445Y-143945D01*
X628321Y-142688D01*
X627955Y-141479D01*
X627359Y-140365D01*
X626558Y-139388D01*
X625581Y-138587D01*
X624467Y-137991D01*
X623258Y-137624D01*
X622001Y-137501D01*
D02*
G37*
G36*
X646457Y-154858D02*
X645754Y-154997D01*
X645159Y-155395D01*
X644761Y-155991D01*
X644743Y-156081D01*
X644233D01*
X644215Y-155991D01*
X643817Y-155395D01*
X643222Y-154997D01*
X642520Y-154858D01*
X641817Y-154997D01*
X641222Y-155395D01*
X640824Y-155991D01*
X640684Y-156693D01*
X640824Y-157395D01*
X641222Y-157991D01*
X641817Y-158388D01*
X642520Y-158528D01*
X642613Y-158510D01*
X642913Y-158960D01*
X642793Y-159140D01*
X642653Y-159843D01*
X642793Y-160545D01*
X643156Y-161088D01*
X643190Y-161201D01*
X643187Y-161739D01*
X642873Y-162208D01*
X642733Y-162910D01*
X642873Y-163613D01*
X643271Y-164208D01*
X643429Y-164314D01*
Y-164915D01*
X643321Y-164987D01*
X642923Y-165582D01*
X642784Y-166285D01*
X642923Y-166987D01*
X643321Y-167582D01*
X643917Y-167980D01*
X644619Y-168120D01*
X645321Y-167980D01*
X645917Y-167582D01*
X646315Y-166987D01*
X646454Y-166285D01*
X646315Y-165582D01*
X645917Y-164987D01*
X645759Y-164881D01*
Y-164280D01*
X645866Y-164208D01*
X646264Y-163613D01*
X646404Y-162910D01*
X646264Y-162208D01*
X645901Y-161665D01*
X645867Y-161552D01*
X645870Y-161014D01*
X646184Y-160545D01*
X646323Y-159843D01*
X646184Y-159140D01*
X646063Y-158960D01*
X646364Y-158510D01*
X646457Y-158528D01*
X647159Y-158388D01*
X647754Y-157991D01*
X648152Y-157395D01*
X648292Y-156693D01*
X648152Y-155991D01*
X647754Y-155395D01*
X647159Y-154997D01*
X646457Y-154858D01*
D02*
G37*
G36*
X162520Y-145659D02*
X161147Y-145794D01*
X159828Y-146195D01*
X158612Y-146844D01*
X157546Y-147719D01*
X156671Y-148785D01*
X156021Y-150001D01*
X155621Y-151321D01*
X155486Y-152693D01*
X155621Y-154065D01*
X156021Y-155385D01*
X156671Y-156601D01*
X157546Y-157667D01*
X158612Y-158541D01*
X159828Y-159191D01*
X161147Y-159592D01*
X162520Y-159727D01*
X163892Y-159592D01*
X165211Y-159191D01*
X166427Y-158541D01*
X167493Y-157667D01*
X168368Y-156601D01*
X169018Y-155385D01*
X169418Y-154065D01*
X169553Y-152693D01*
X169418Y-151321D01*
X169018Y-150001D01*
X168368Y-148785D01*
X167493Y-147719D01*
X166427Y-146844D01*
X165211Y-146195D01*
X163892Y-145794D01*
X162520Y-145659D01*
D02*
G37*
G36*
X518337Y-157799D02*
X517635Y-157938D01*
X517039Y-158336D01*
X516642Y-158932D01*
X516502Y-159634D01*
X516642Y-160336D01*
X516931Y-160769D01*
X517039Y-160932D01*
X516759Y-161344D01*
X516405Y-161107D01*
X515702Y-160968D01*
X515000Y-161107D01*
X514405Y-161505D01*
X514007Y-162100D01*
X513867Y-162803D01*
X514007Y-163505D01*
X514405Y-164100D01*
X515000Y-164498D01*
X515702Y-164638D01*
X516405Y-164498D01*
X517000Y-164100D01*
X517398Y-163505D01*
X517538Y-162803D01*
X517398Y-162100D01*
X517109Y-161668D01*
X517000Y-161505D01*
X517280Y-161092D01*
X517635Y-161329D01*
X518337Y-161469D01*
X519039Y-161329D01*
X519635Y-160932D01*
X520033Y-160336D01*
X520172Y-159634D01*
X520033Y-158932D01*
X519635Y-158336D01*
X519039Y-157938D01*
X518337Y-157799D01*
D02*
G37*
G36*
X406528Y-155931D02*
X405825Y-156071D01*
X405230Y-156469D01*
X404832Y-157064D01*
X404692Y-157767D01*
X404832Y-158469D01*
X405230Y-159064D01*
X405506Y-159249D01*
X405780Y-159723D01*
X405740Y-159955D01*
X405645Y-160433D01*
X405785Y-161135D01*
X406008Y-161470D01*
X405803Y-161921D01*
X405683Y-161981D01*
X405657Y-161975D01*
X405230Y-161690D01*
X404528Y-161551D01*
X403825Y-161690D01*
X403230Y-162088D01*
X402832Y-162683D01*
X402692Y-163386D01*
X402832Y-164088D01*
X403230Y-164683D01*
X403825Y-165081D01*
X404528Y-165221D01*
X405230Y-165081D01*
X405657Y-164796D01*
X406004Y-164722D01*
X406351Y-164796D01*
X406778Y-165081D01*
X407480Y-165221D01*
X408183Y-165081D01*
X408778Y-164683D01*
X409176Y-164088D01*
X409316Y-163386D01*
X409176Y-162683D01*
X408778Y-162088D01*
Y-161731D01*
X409176Y-161135D01*
X409316Y-160433D01*
X409176Y-159731D01*
X408778Y-159135D01*
X408502Y-158951D01*
X408228Y-158477D01*
X408268Y-158245D01*
X408363Y-157767D01*
X408223Y-157064D01*
X407825Y-156469D01*
X407230Y-156071D01*
X406528Y-155931D01*
D02*
G37*
G36*
X679921Y-158401D02*
X679219Y-158541D01*
X678623Y-158939D01*
X678226Y-159534D01*
X678086Y-160236D01*
X678226Y-160939D01*
X678623Y-161534D01*
X679219Y-161932D01*
X679921Y-162072D01*
X680624Y-161932D01*
X681219Y-161534D01*
X681617Y-160939D01*
X681756Y-160236D01*
X681617Y-159534D01*
X681219Y-158939D01*
X680624Y-158541D01*
X679921Y-158401D01*
D02*
G37*
G36*
X-3528Y-152395D02*
X-13402D01*
Y-162269D01*
X-3528D01*
Y-152395D01*
D02*
G37*
G36*
X470285Y-158353D02*
X469472Y-158514D01*
X468783Y-158975D01*
X468322Y-159664D01*
X468161Y-160477D01*
X468322Y-161289D01*
X468783Y-161978D01*
X469472Y-162439D01*
X470285Y-162600D01*
X471097Y-162439D01*
X471786Y-161978D01*
X472247Y-161289D01*
X472408Y-160477D01*
X472247Y-159664D01*
X471786Y-158975D01*
X471097Y-158514D01*
X470285Y-158353D01*
D02*
G37*
G36*
X391545D02*
X390732Y-158514D01*
X390043Y-158975D01*
X389582Y-159664D01*
X389421Y-160477D01*
X389582Y-161289D01*
X390043Y-161978D01*
X390732Y-162439D01*
X391545Y-162600D01*
X392357Y-162439D01*
X393046Y-161978D01*
X393507Y-161289D01*
X393668Y-160477D01*
X393507Y-159664D01*
X393046Y-158975D01*
X392357Y-158514D01*
X391545Y-158353D01*
D02*
G37*
G36*
X533015Y-148825D02*
X531662Y-148958D01*
X530360Y-149353D01*
X529160Y-149995D01*
X528109Y-150857D01*
X527246Y-151909D01*
X526605Y-153109D01*
X526210Y-154410D01*
X526076Y-155764D01*
X526210Y-157118D01*
X526605Y-158419D01*
X527246Y-159619D01*
X528109Y-160671D01*
X529160Y-161533D01*
X530360Y-162175D01*
X531662Y-162570D01*
X533015Y-162703D01*
X534369Y-162570D01*
X535671Y-162175D01*
X536870Y-161533D01*
X537922Y-160671D01*
X538785Y-159619D01*
X539426Y-158419D01*
X539821Y-157118D01*
X539954Y-155764D01*
X539821Y-154410D01*
X539426Y-153109D01*
X538785Y-151909D01*
X537922Y-150857D01*
X536870Y-149995D01*
X535671Y-149353D01*
X534369Y-148958D01*
X533015Y-148825D01*
D02*
G37*
G36*
X336415D02*
X335062Y-148958D01*
X333760Y-149353D01*
X332560Y-149995D01*
X331509Y-150857D01*
X330646Y-151909D01*
X330005Y-153109D01*
X329610Y-154410D01*
X329476Y-155764D01*
X329610Y-157118D01*
X330005Y-158419D01*
X330646Y-159619D01*
X331509Y-160671D01*
X332560Y-161533D01*
X333760Y-162175D01*
X335062Y-162570D01*
X336415Y-162703D01*
X337769Y-162570D01*
X339071Y-162175D01*
X340270Y-161533D01*
X341322Y-160671D01*
X342185Y-159619D01*
X342826Y-158419D01*
X343221Y-157118D01*
X343354Y-155764D01*
X343221Y-154410D01*
X342826Y-153109D01*
X342185Y-151909D01*
X341322Y-150857D01*
X340270Y-149995D01*
X339071Y-149353D01*
X337769Y-148958D01*
X336415Y-148825D01*
D02*
G37*
G36*
X302362Y-150664D02*
X301186Y-150780D01*
X300055Y-151123D01*
X299013Y-151680D01*
X298099Y-152430D01*
X297349Y-153343D01*
X296792Y-154386D01*
X296449Y-155517D01*
X296333Y-156693D01*
X296449Y-157869D01*
X296792Y-159000D01*
X297349Y-160043D01*
X298099Y-160956D01*
X299013Y-161706D01*
X300055Y-162263D01*
X301186Y-162606D01*
X302362Y-162722D01*
X303538Y-162606D01*
X304669Y-162263D01*
X305712Y-161706D01*
X306625Y-160956D01*
X307375Y-160043D01*
X307932Y-159000D01*
X308275Y-157869D01*
X308391Y-156693D01*
X308275Y-155517D01*
X307932Y-154386D01*
X307375Y-153343D01*
X306625Y-152430D01*
X305712Y-151680D01*
X304669Y-151123D01*
X303538Y-150780D01*
X302362Y-150664D01*
D02*
G37*
G36*
X142520D02*
X141343Y-150780D01*
X140213Y-151123D01*
X139170Y-151680D01*
X138257Y-152430D01*
X137507Y-153343D01*
X136950Y-154386D01*
X136607Y-155517D01*
X136491Y-156693D01*
X136607Y-157869D01*
X136950Y-159000D01*
X137507Y-160043D01*
X138257Y-160956D01*
X139170Y-161706D01*
X140213Y-162263D01*
X141343Y-162606D01*
X142520Y-162722D01*
X143696Y-162606D01*
X144827Y-162263D01*
X145869Y-161706D01*
X146783Y-160956D01*
X147533Y-160043D01*
X148090Y-159000D01*
X148433Y-157869D01*
X148549Y-156693D01*
X148433Y-155517D01*
X148090Y-154386D01*
X147533Y-153343D01*
X146783Y-152430D01*
X145869Y-151680D01*
X144827Y-151123D01*
X143696Y-150780D01*
X142520Y-150664D01*
D02*
G37*
G36*
X684646Y-159976D02*
X683943Y-160116D01*
X683348Y-160513D01*
X682950Y-161109D01*
X682810Y-161811D01*
X682950Y-162513D01*
X683348Y-163109D01*
X683943Y-163507D01*
X684646Y-163646D01*
X685348Y-163507D01*
X685943Y-163109D01*
X686341Y-162513D01*
X686481Y-161811D01*
X686341Y-161109D01*
X685943Y-160513D01*
X685348Y-160116D01*
X684646Y-159976D01*
D02*
G37*
G36*
X89567Y-164535D02*
X88865Y-164674D01*
X88362Y-165010D01*
X87870Y-164681D01*
X87167Y-164542D01*
X86465Y-164681D01*
X85869Y-165079D01*
X85472Y-165675D01*
X85332Y-166377D01*
X85472Y-167079D01*
X85814Y-167592D01*
X85264Y-167959D01*
X84867Y-168555D01*
X84727Y-169257D01*
X84867Y-169959D01*
X85264Y-170555D01*
X85860Y-170952D01*
X86562Y-171092D01*
X87265Y-170952D01*
X87860Y-170555D01*
X88258Y-169959D01*
X88398Y-169257D01*
X88258Y-168555D01*
X87915Y-168042D01*
X88372Y-167737D01*
X88865Y-168066D01*
X89567Y-168205D01*
X90270Y-168066D01*
X90865Y-167668D01*
X91263Y-167072D01*
X91403Y-166370D01*
X91263Y-165668D01*
X90865Y-165072D01*
X90270Y-164674D01*
X89567Y-164535D01*
D02*
G37*
G36*
X689370Y-159582D02*
X688668Y-159722D01*
X688072Y-160120D01*
X687675Y-160715D01*
X687535Y-161417D01*
X687675Y-162120D01*
X688072Y-162715D01*
X688234Y-162823D01*
X688466Y-163269D01*
X688344Y-163452D01*
X688068Y-163865D01*
X687928Y-164567D01*
X688068Y-165269D01*
X688466Y-165865D01*
X688725Y-166038D01*
Y-166639D01*
X688466Y-166813D01*
X688068Y-167408D01*
X687928Y-168110D01*
X688068Y-168813D01*
X688466Y-169408D01*
X689061Y-169806D01*
X689764Y-169946D01*
X690466Y-169806D01*
X691061Y-169408D01*
X691459Y-168813D01*
X691599Y-168110D01*
X691459Y-167408D01*
X691061Y-166813D01*
X690802Y-166639D01*
Y-166038D01*
X691061Y-165865D01*
X691459Y-165269D01*
X691599Y-164567D01*
X691459Y-163865D01*
X691061Y-163269D01*
X690900Y-163161D01*
X690668Y-162715D01*
X690790Y-162532D01*
X691066Y-162120D01*
X691205Y-161417D01*
X691066Y-160715D01*
X690668Y-160120D01*
X690072Y-159722D01*
X689370Y-159582D01*
D02*
G37*
G36*
X284862Y-157759D02*
X283490Y-157894D01*
X282171Y-158294D01*
X280954Y-158944D01*
X279889Y-159819D01*
X279014Y-160885D01*
X278364Y-162101D01*
X277963Y-163421D01*
X277828Y-164793D01*
X277963Y-166165D01*
X278364Y-167485D01*
X279014Y-168701D01*
X279889Y-169767D01*
X280954Y-170641D01*
X282171Y-171291D01*
X283490Y-171692D01*
X284862Y-171827D01*
X286234Y-171692D01*
X287554Y-171291D01*
X288770Y-170641D01*
X289836Y-169767D01*
X290711Y-168701D01*
X291361Y-167485D01*
X291761Y-166165D01*
X291896Y-164793D01*
X291761Y-163421D01*
X291361Y-162101D01*
X290711Y-160885D01*
X289836Y-159819D01*
X288770Y-158944D01*
X287554Y-158294D01*
X286234Y-157894D01*
X284862Y-157759D01*
D02*
G37*
G36*
X30512Y-168440D02*
X29809Y-168580D01*
X29214Y-168978D01*
X28816Y-169573D01*
X28677Y-170276D01*
X28816Y-170978D01*
X29214Y-171573D01*
X29809Y-171971D01*
X30512Y-172111D01*
X31214Y-171971D01*
X31809Y-171573D01*
X32207Y-170978D01*
X32347Y-170276D01*
X32207Y-169573D01*
X31809Y-168978D01*
X31214Y-168580D01*
X30512Y-168440D01*
D02*
G37*
G36*
X644488Y-168637D02*
X643786Y-168777D01*
X643190Y-169175D01*
X642793Y-169770D01*
X642653Y-170472D01*
X642793Y-171175D01*
X643190Y-171770D01*
X643786Y-172168D01*
X644488Y-172308D01*
X645190Y-172168D01*
X645786Y-171770D01*
X646184Y-171175D01*
X646323Y-170472D01*
X646184Y-169770D01*
X645786Y-169175D01*
X645190Y-168777D01*
X644488Y-168637D01*
D02*
G37*
G36*
X413440Y-173015D02*
X412737Y-173154D01*
X412148Y-173548D01*
X411745Y-173278D01*
X411043Y-173139D01*
X410340Y-173278D01*
X409745Y-173676D01*
X409347Y-174272D01*
X409207Y-174974D01*
X409347Y-175676D01*
X409745Y-176272D01*
X410340Y-176670D01*
X411043Y-176809D01*
X411745Y-176670D01*
X412334Y-176276D01*
X412737Y-176546D01*
X413440Y-176685D01*
X414142Y-176546D01*
X414737Y-176148D01*
X415135Y-175552D01*
X415275Y-174850D01*
X415135Y-174148D01*
X414737Y-173552D01*
X414142Y-173154D01*
X413440Y-173015D01*
D02*
G37*
G36*
X404823Y-173509D02*
X404120Y-173649D01*
X403543Y-174034D01*
X402966Y-173649D01*
X402264Y-173509D01*
X401561Y-173649D01*
X400966Y-174046D01*
X400568Y-174642D01*
X400428Y-175344D01*
X400568Y-176046D01*
X400966Y-176642D01*
X401561Y-177040D01*
X402264Y-177179D01*
X402966Y-177040D01*
X403543Y-176654D01*
X404120Y-177040D01*
X404823Y-177179D01*
X405525Y-177040D01*
X406121Y-176642D01*
X406518Y-176046D01*
X406658Y-175344D01*
X406518Y-174642D01*
X406121Y-174046D01*
X405525Y-173649D01*
X404823Y-173509D01*
D02*
G37*
G36*
X437697Y-173410D02*
X436995Y-173550D01*
X436399Y-173948D01*
X436049Y-174471D01*
X435778Y-174511D01*
X435506Y-174471D01*
X435156Y-173948D01*
X434561Y-173550D01*
X433858Y-173410D01*
X433156Y-173550D01*
X432561Y-173948D01*
X431959Y-173949D01*
X431509Y-173649D01*
X430807Y-173509D01*
X430105Y-173649D01*
X429509Y-174046D01*
X429297Y-174364D01*
X429295Y-174365D01*
X428718Y-174330D01*
X428463Y-173948D01*
X427868Y-173550D01*
X427165Y-173410D01*
X426463Y-173550D01*
X425868Y-173948D01*
X425470Y-174543D01*
X425330Y-175246D01*
X425470Y-175948D01*
X425868Y-176543D01*
X426463Y-176941D01*
X427165Y-177081D01*
X427868Y-176941D01*
X428463Y-176543D01*
X428676Y-176225D01*
X428677Y-176225D01*
X429254Y-176260D01*
X429509Y-176642D01*
X430105Y-177040D01*
X430807Y-177179D01*
X431509Y-177040D01*
X432105Y-176642D01*
X432707Y-176641D01*
X433156Y-176941D01*
X433858Y-177081D01*
X434561Y-176941D01*
X435156Y-176543D01*
X435506Y-176020D01*
X435778Y-175980D01*
X436049Y-176020D01*
X436399Y-176543D01*
X436995Y-176941D01*
X437697Y-177081D01*
X438399Y-176941D01*
X438995Y-176543D01*
X439392Y-175948D01*
X439532Y-175246D01*
X439392Y-174543D01*
X438995Y-173948D01*
X438399Y-173550D01*
X437697Y-173410D01*
D02*
G37*
G36*
X421596Y-173198D02*
X420894Y-173338D01*
X420298Y-173736D01*
X419901Y-174331D01*
X419835Y-174662D01*
X419325D01*
X419292Y-174495D01*
X418894Y-173899D01*
X418299Y-173501D01*
X417596Y-173362D01*
X416894Y-173501D01*
X416298Y-173899D01*
X415901Y-174495D01*
X415761Y-175197D01*
X415901Y-175899D01*
X416298Y-176495D01*
X416894Y-176892D01*
X417596Y-177032D01*
X418299Y-176892D01*
X418894Y-176495D01*
X419292Y-175899D01*
X419358Y-175568D01*
X419867D01*
X419901Y-175736D01*
X420298Y-176331D01*
X420894Y-176729D01*
X421596Y-176869D01*
X422299Y-176729D01*
X422894Y-176331D01*
X423292Y-175736D01*
X423431Y-175034D01*
X423292Y-174331D01*
X422894Y-173736D01*
X422299Y-173338D01*
X421596Y-173198D01*
D02*
G37*
G36*
X530027Y-171152D02*
X529325Y-171292D01*
X528729Y-171690D01*
X528332Y-172285D01*
X528192Y-172987D01*
X528332Y-173690D01*
X528729Y-174285D01*
X529325Y-174683D01*
X530027Y-174823D01*
X530729Y-174683D01*
X531325Y-174285D01*
X531723Y-173690D01*
X531862Y-172987D01*
X531723Y-172285D01*
X531325Y-171690D01*
X530729Y-171292D01*
X530027Y-171152D01*
D02*
G37*
G36*
X476945Y-171393D02*
X476243Y-171533D01*
X475647Y-171931D01*
X475250Y-172526D01*
X475110Y-173228D01*
X475250Y-173931D01*
X475647Y-174526D01*
X476243Y-174924D01*
X476945Y-175064D01*
X477648Y-174924D01*
X478243Y-174526D01*
X478641Y-173931D01*
X478781Y-173228D01*
X478641Y-172526D01*
X478243Y-171931D01*
X477648Y-171533D01*
X476945Y-171393D01*
D02*
G37*
G36*
X450850Y-172292D02*
X450147Y-172431D01*
X449552Y-172829D01*
X449154Y-173424D01*
X449014Y-174127D01*
X449154Y-174829D01*
X449552Y-175425D01*
X450147Y-175822D01*
X450850Y-175962D01*
X451552Y-175822D01*
X452147Y-175425D01*
X452545Y-174829D01*
X452685Y-174127D01*
X452545Y-173424D01*
X452147Y-172829D01*
X451552Y-172431D01*
X450850Y-172292D01*
D02*
G37*
G36*
X443898Y-173214D02*
X443195Y-173353D01*
X442600Y-173751D01*
X442202Y-174346D01*
X442062Y-175049D01*
X442202Y-175751D01*
X442600Y-176347D01*
X443195Y-176744D01*
X443898Y-176884D01*
X444600Y-176744D01*
X445195Y-176347D01*
X445593Y-175751D01*
X445733Y-175049D01*
X445593Y-174346D01*
X445195Y-173751D01*
X444600Y-173353D01*
X443898Y-173214D01*
D02*
G37*
G36*
X469390Y-173312D02*
X468687Y-173452D01*
X468092Y-173849D01*
X467694Y-174445D01*
X467555Y-175147D01*
X467694Y-175850D01*
X468092Y-176445D01*
X468687Y-176843D01*
X469390Y-176982D01*
X470092Y-176843D01*
X470687Y-176445D01*
X471085Y-175850D01*
X471225Y-175147D01*
X471085Y-174445D01*
X470687Y-173849D01*
X470092Y-173452D01*
X469390Y-173312D01*
D02*
G37*
G36*
X86614Y-173362D02*
X85912Y-173501D01*
X85316Y-173899D01*
X84919Y-174495D01*
X84779Y-175197D01*
X84919Y-175899D01*
X85316Y-176495D01*
X85912Y-176892D01*
X86614Y-177032D01*
X87317Y-176892D01*
X87912Y-176495D01*
X88310Y-175899D01*
X88449Y-175197D01*
X88310Y-174495D01*
X87912Y-173899D01*
X87317Y-173501D01*
X86614Y-173362D01*
D02*
G37*
G36*
X457283Y-173312D02*
X456581Y-173452D01*
X455986Y-173849D01*
X455588Y-174445D01*
X455448Y-175147D01*
X455588Y-175850D01*
X455986Y-176445D01*
X456581Y-176843D01*
X457283Y-176982D01*
X457986Y-176843D01*
X458581Y-176445D01*
X458870Y-176717D01*
X458888Y-176745D01*
X459484Y-177143D01*
X460186Y-177283D01*
X460888Y-177143D01*
X461484Y-176745D01*
X461881Y-176150D01*
X462021Y-175448D01*
X461881Y-174745D01*
X461484Y-174150D01*
X460888Y-173752D01*
X460186Y-173612D01*
X459484Y-173752D01*
X458888Y-174150D01*
X458782D01*
X458581Y-173849D01*
X457986Y-173452D01*
X457283Y-173312D01*
D02*
G37*
G36*
X533044Y-174390D02*
X532342Y-174530D01*
X531746Y-174927D01*
X531348Y-175523D01*
X531209Y-176225D01*
X531348Y-176927D01*
X531746Y-177523D01*
X532342Y-177921D01*
X533044Y-178060D01*
X533746Y-177921D01*
X534342Y-177523D01*
X534739Y-176927D01*
X534879Y-176225D01*
X534739Y-175523D01*
X534342Y-174927D01*
X533746Y-174530D01*
X533044Y-174390D01*
D02*
G37*
G36*
X474016Y-174543D02*
X473313Y-174682D01*
X472718Y-175080D01*
X472320Y-175676D01*
X472181Y-176378D01*
X472320Y-177080D01*
X472718Y-177676D01*
X473313Y-178074D01*
X474016Y-178213D01*
X474718Y-178074D01*
X475314Y-177676D01*
X475711Y-177080D01*
X475851Y-176378D01*
X475711Y-175676D01*
X475314Y-175080D01*
X474718Y-174682D01*
X474016Y-174543D01*
D02*
G37*
G36*
X423461Y-177034D02*
X422758Y-177173D01*
X422163Y-177571D01*
X421765Y-178167D01*
X421626Y-178869D01*
X421765Y-179571D01*
X422163Y-180167D01*
X422758Y-180565D01*
X423461Y-180704D01*
X424163Y-180565D01*
X424758Y-180167D01*
X425156Y-179571D01*
X425296Y-178869D01*
X425156Y-178167D01*
X424758Y-177571D01*
X424163Y-177173D01*
X423461Y-177034D01*
D02*
G37*
G36*
X74803Y-177299D02*
X74101Y-177438D01*
X73505Y-177836D01*
X73108Y-178431D01*
X72968Y-179134D01*
X73108Y-179836D01*
X73505Y-180432D01*
X74101Y-180829D01*
X74803Y-180969D01*
X75506Y-180829D01*
X76101Y-180432D01*
X76499Y-179836D01*
X76638Y-179134D01*
X76499Y-178431D01*
X76101Y-177836D01*
X75506Y-177438D01*
X74803Y-177299D01*
D02*
G37*
G36*
X63976D02*
X63274Y-177438D01*
X62679Y-177836D01*
X62281Y-178431D01*
X62141Y-179134D01*
X62281Y-179836D01*
X62679Y-180432D01*
X63274Y-180829D01*
X63976Y-180969D01*
X64679Y-180829D01*
X65274Y-180432D01*
X65672Y-179836D01*
X65812Y-179134D01*
X65672Y-178431D01*
X65274Y-177836D01*
X64679Y-177438D01*
X63976Y-177299D01*
D02*
G37*
G36*
X499111Y-177693D02*
X498408Y-177833D01*
X497813Y-178231D01*
X497415Y-178826D01*
X497275Y-179528D01*
X497415Y-180231D01*
X497813Y-180826D01*
X498408Y-181224D01*
X499111Y-181363D01*
X499813Y-181224D01*
X500408Y-180826D01*
X500806Y-180231D01*
X500946Y-179528D01*
X500806Y-178826D01*
X500408Y-178231D01*
X499813Y-177833D01*
X499111Y-177693D01*
D02*
G37*
G36*
X80709Y-178283D02*
X80006Y-178423D01*
X79411Y-178820D01*
X79013Y-179416D01*
X78873Y-180118D01*
X79013Y-180820D01*
X79411Y-181416D01*
X80006Y-181814D01*
X80709Y-181953D01*
X81411Y-181814D01*
X82006Y-181416D01*
X82404Y-180820D01*
X82544Y-180118D01*
X82404Y-179416D01*
X82006Y-178820D01*
X81411Y-178423D01*
X80709Y-178283D01*
D02*
G37*
G36*
X498819Y-182023D02*
X498117Y-182163D01*
X497521Y-182561D01*
X497123Y-183156D01*
X496984Y-183858D01*
X497123Y-184561D01*
X497521Y-185156D01*
X498117Y-185554D01*
X498819Y-185694D01*
X499521Y-185554D01*
X500117Y-185156D01*
X500515Y-184561D01*
X500654Y-183858D01*
X500515Y-183156D01*
X500117Y-182561D01*
X499521Y-182163D01*
X498819Y-182023D01*
D02*
G37*
G36*
X-23622Y-175330D02*
X-24324Y-175470D01*
X-24920Y-175868D01*
X-25318Y-176463D01*
X-25457Y-177165D01*
X-25318Y-177868D01*
X-24920Y-178463D01*
X-24324Y-178861D01*
X-24234Y-178879D01*
Y-179389D01*
X-24324Y-179407D01*
X-24920Y-179805D01*
X-25318Y-180400D01*
X-25457Y-181102D01*
X-25318Y-181805D01*
X-25032Y-182231D01*
X-24958Y-182579D01*
X-25032Y-182926D01*
X-25318Y-183353D01*
X-25457Y-184055D01*
X-25318Y-184757D01*
X-24920Y-185353D01*
X-24324Y-185751D01*
X-24234Y-185769D01*
Y-186278D01*
X-24324Y-186297D01*
X-24920Y-186694D01*
X-25318Y-187290D01*
X-25457Y-187992D01*
X-25318Y-188695D01*
X-24920Y-189290D01*
X-24324Y-189688D01*
X-23622Y-189827D01*
X-22920Y-189688D01*
X-22324Y-189290D01*
X-21926Y-188695D01*
X-21787Y-187992D01*
X-21926Y-187290D01*
X-22324Y-186694D01*
X-22920Y-186297D01*
X-23010Y-186278D01*
Y-185769D01*
X-22920Y-185751D01*
X-22324Y-185353D01*
X-21926Y-184757D01*
X-21787Y-184055D01*
X-21926Y-183353D01*
X-22212Y-182926D01*
X-22286Y-182579D01*
X-22212Y-182231D01*
X-21926Y-181805D01*
X-21787Y-181102D01*
X-21926Y-180400D01*
X-22324Y-179805D01*
X-22920Y-179407D01*
X-23010Y-179389D01*
Y-178879D01*
X-22920Y-178861D01*
X-22324Y-178463D01*
X-21926Y-177868D01*
X-21787Y-177165D01*
X-21926Y-176463D01*
X-22324Y-175868D01*
X-22920Y-175470D01*
X-23622Y-175330D01*
D02*
G37*
G36*
X498693Y-186515D02*
X497991Y-186655D01*
X497395Y-187053D01*
X496997Y-187648D01*
X496858Y-188351D01*
X496997Y-189053D01*
X497395Y-189648D01*
X497991Y-190046D01*
X498693Y-190186D01*
X499395Y-190046D01*
X499991Y-189648D01*
X500388Y-189053D01*
X500528Y-188351D01*
X500388Y-187648D01*
X499991Y-187053D01*
X499395Y-186655D01*
X498693Y-186515D01*
D02*
G37*
G36*
X549298Y-190153D02*
X548596Y-190292D01*
X548001Y-190690D01*
X547603Y-191286D01*
X547463Y-191988D01*
X547603Y-192690D01*
X548001Y-193286D01*
X548596Y-193683D01*
X549298Y-193823D01*
X550001Y-193683D01*
X550596Y-193286D01*
X550994Y-192690D01*
X551134Y-191988D01*
X550994Y-191286D01*
X550596Y-190690D01*
X550001Y-190292D01*
X549298Y-190153D01*
D02*
G37*
G36*
X569291Y-192259D02*
X568589Y-192399D01*
X567994Y-192797D01*
X567596Y-193392D01*
X567456Y-194095D01*
X567596Y-194797D01*
X567994Y-195392D01*
X568589Y-195790D01*
X569291Y-195930D01*
X569994Y-195790D01*
X570589Y-195392D01*
X570987Y-194797D01*
X571127Y-194095D01*
X570987Y-193392D01*
X570589Y-192797D01*
X569994Y-192399D01*
X569291Y-192259D01*
D02*
G37*
G36*
X358661Y-192653D02*
X357959Y-192793D01*
X357364Y-193191D01*
X356966Y-193786D01*
X356826Y-194488D01*
X356966Y-195191D01*
X357364Y-195786D01*
X357959Y-196184D01*
X358661Y-196324D01*
X359364Y-196184D01*
X359959Y-195786D01*
X360357Y-195191D01*
X360497Y-194488D01*
X360357Y-193786D01*
X359959Y-193191D01*
X359364Y-192793D01*
X358661Y-192653D01*
D02*
G37*
G36*
X340904Y-192546D02*
X340092Y-192708D01*
X339403Y-193168D01*
X338942Y-193857D01*
X338780Y-194670D01*
X338942Y-195483D01*
X339403Y-196172D01*
X340092Y-196632D01*
X340904Y-196794D01*
X341717Y-196632D01*
X342406Y-196172D01*
X342866Y-195483D01*
X343028Y-194670D01*
X342866Y-193857D01*
X342406Y-193168D01*
X341717Y-192708D01*
X340904Y-192546D01*
D02*
G37*
G36*
X528395Y-192556D02*
X527583Y-192718D01*
X526894Y-193178D01*
X526433Y-193867D01*
X526271Y-194680D01*
X526433Y-195492D01*
X526894Y-196181D01*
X527583Y-196642D01*
X528395Y-196804D01*
X529208Y-196642D01*
X529897Y-196181D01*
X530358Y-195492D01*
X530519Y-194680D01*
X530358Y-193867D01*
X529897Y-193178D01*
X529208Y-192718D01*
X528395Y-192556D01*
D02*
G37*
G36*
X598425Y-196984D02*
X597723Y-197123D01*
X597127Y-197521D01*
X597100Y-197562D01*
X596600D01*
X596573Y-197521D01*
X595978Y-197123D01*
X595276Y-196984D01*
X594573Y-197123D01*
X593978Y-197521D01*
X593951Y-197562D01*
X593451D01*
X593424Y-197521D01*
X592828Y-197123D01*
X592126Y-196984D01*
X591424Y-197123D01*
X590945Y-197443D01*
X590466Y-197123D01*
X589764Y-196984D01*
X589061Y-197123D01*
X588771Y-197318D01*
X588386Y-197486D01*
X588001Y-197318D01*
X587710Y-197123D01*
X587008Y-196984D01*
X586306Y-197123D01*
X585710Y-197521D01*
X585312Y-198117D01*
X585173Y-198819D01*
X585312Y-199521D01*
X585710Y-200117D01*
X586306Y-200515D01*
X587008Y-200654D01*
X587710Y-200515D01*
X588001Y-200320D01*
X588386Y-200152D01*
X588771Y-200320D01*
X589061Y-200515D01*
X589764Y-200654D01*
X590466Y-200515D01*
X590945Y-200195D01*
X591424Y-200515D01*
X592126Y-200654D01*
X592828Y-200515D01*
X593424Y-200117D01*
X593451Y-200076D01*
X593951D01*
X593978Y-200117D01*
X594573Y-200515D01*
X595276Y-200654D01*
X595978Y-200515D01*
X596573Y-200117D01*
X596600Y-200076D01*
X597100D01*
X597127Y-200117D01*
X597723Y-200515D01*
X598425Y-200654D01*
X599127Y-200515D01*
X599723Y-200117D01*
X600121Y-199521D01*
X600260Y-198819D01*
X600121Y-198117D01*
X599723Y-197521D01*
X599127Y-197123D01*
X598425Y-196984D01*
D02*
G37*
G36*
X416835Y-194746D02*
X416132Y-194885D01*
X415537Y-195283D01*
X415139Y-195879D01*
X414999Y-196581D01*
X415139Y-197283D01*
X415537Y-197879D01*
X416132Y-198276D01*
X416835Y-198416D01*
X417537Y-198276D01*
X418132Y-197879D01*
X418530Y-197283D01*
X418670Y-196581D01*
X418530Y-195879D01*
X418132Y-195283D01*
X417537Y-194885D01*
X416835Y-194746D01*
D02*
G37*
G36*
X411811Y-195015D02*
X411109Y-195155D01*
X410513Y-195553D01*
X410115Y-196148D01*
X409976Y-196850D01*
X410115Y-197553D01*
X410513Y-198148D01*
X411109Y-198546D01*
X411811Y-198686D01*
X412513Y-198546D01*
X413109Y-198148D01*
X413507Y-197553D01*
X413646Y-196850D01*
X413507Y-196148D01*
X413109Y-195553D01*
X412513Y-195155D01*
X411811Y-195015D01*
D02*
G37*
G36*
X326966Y-193336D02*
X326264Y-193476D01*
X325669Y-193873D01*
X325271Y-194469D01*
X325131Y-195171D01*
X325271Y-195873D01*
X325605Y-196374D01*
X325273Y-196871D01*
X325133Y-197573D01*
X325273Y-198275D01*
X325671Y-198871D01*
X326266Y-199269D01*
X326969Y-199408D01*
X327671Y-199269D01*
X328266Y-198871D01*
X328664Y-198275D01*
X328804Y-197573D01*
X328664Y-196871D01*
X328330Y-196371D01*
X328662Y-195873D01*
X328802Y-195171D01*
X328662Y-194469D01*
X328264Y-193873D01*
X327669Y-193476D01*
X326966Y-193336D01*
D02*
G37*
G36*
X581496Y-196984D02*
X580794Y-197123D01*
X580198Y-197521D01*
X579801Y-198117D01*
X579661Y-198819D01*
X579801Y-199521D01*
X580198Y-200117D01*
X580794Y-200515D01*
X581496Y-200654D01*
X582198Y-200515D01*
X582794Y-200117D01*
X583192Y-199521D01*
X583331Y-198819D01*
X583192Y-198117D01*
X582794Y-197521D01*
X582198Y-197123D01*
X581496Y-196984D01*
D02*
G37*
G36*
X573622D02*
X572920Y-197123D01*
X572324Y-197521D01*
X571926Y-198117D01*
X571787Y-198819D01*
X571926Y-199521D01*
X572324Y-200117D01*
X572920Y-200515D01*
X573622Y-200654D01*
X574324Y-200515D01*
X574920Y-200117D01*
X575318Y-199521D01*
X575457Y-198819D01*
X575318Y-198117D01*
X574920Y-197521D01*
X574324Y-197123D01*
X573622Y-196984D01*
D02*
G37*
G36*
X675591Y-194621D02*
X674888Y-194761D01*
X674293Y-195159D01*
X673895Y-195754D01*
X673755Y-196457D01*
X673895Y-197159D01*
X674293Y-197754D01*
X674390Y-197819D01*
X674417Y-197945D01*
X674355Y-198398D01*
X673899Y-198702D01*
X673501Y-199298D01*
X673362Y-200000D01*
X673501Y-200702D01*
X673899Y-201298D01*
X674495Y-201696D01*
X675197Y-201835D01*
X675899Y-201696D01*
X676495Y-201298D01*
X676668Y-201038D01*
X677269D01*
X677442Y-201298D01*
X678038Y-201696D01*
X678740Y-201835D01*
X679443Y-201696D01*
X680005Y-201320D01*
X680152Y-201257D01*
X680478D01*
X680625Y-201320D01*
X681187Y-201696D01*
X681890Y-201835D01*
X682592Y-201696D01*
X683187Y-201298D01*
X683585Y-200702D01*
X683725Y-200000D01*
X683585Y-199298D01*
X683209Y-198735D01*
X683147Y-198588D01*
Y-198262D01*
X683209Y-198116D01*
X683585Y-197553D01*
X683725Y-196850D01*
X683585Y-196148D01*
X683187Y-195553D01*
X682592Y-195155D01*
X681890Y-195015D01*
X681187Y-195155D01*
X680625Y-195531D01*
X680478Y-195593D01*
X680152D01*
X680005Y-195531D01*
X679443Y-195155D01*
X678740Y-195015D01*
X678038Y-195155D01*
X677625Y-195431D01*
X677442Y-195553D01*
X676996Y-195320D01*
X676888Y-195159D01*
X676293Y-194761D01*
X675591Y-194621D01*
D02*
G37*
G36*
X372016Y-198952D02*
X371313Y-199092D01*
X370718Y-199490D01*
X370320Y-200085D01*
X370181Y-200787D01*
X370320Y-201490D01*
X370718Y-202085D01*
X371313Y-202483D01*
X372016Y-202623D01*
X372718Y-202483D01*
X373313Y-202085D01*
X373711Y-201490D01*
X373851Y-200787D01*
X373711Y-200085D01*
X373313Y-199490D01*
X372718Y-199092D01*
X372016Y-198952D01*
D02*
G37*
G36*
X509842Y-193883D02*
X509140Y-194023D01*
X508545Y-194420D01*
X508147Y-195016D01*
X508007Y-195718D01*
X508147Y-196420D01*
X508335Y-196702D01*
X508147Y-196984D01*
X508007Y-197687D01*
X508147Y-198389D01*
X508335Y-198671D01*
X508147Y-198953D01*
X508007Y-199655D01*
X508147Y-200357D01*
X508335Y-200639D01*
X508147Y-200921D01*
X508007Y-201624D01*
X508147Y-202326D01*
X508545Y-202921D01*
X509140Y-203319D01*
X509842Y-203459D01*
X510545Y-203319D01*
X511140Y-202921D01*
X511538Y-202326D01*
X511678Y-201624D01*
X511538Y-200921D01*
X511350Y-200639D01*
X511538Y-200357D01*
X511678Y-199655D01*
X511538Y-198953D01*
X511350Y-198671D01*
X511538Y-198389D01*
X511678Y-197687D01*
X511538Y-196984D01*
X511350Y-196702D01*
X511538Y-196420D01*
X511678Y-195718D01*
X511538Y-195016D01*
X511140Y-194420D01*
X510545Y-194023D01*
X509842Y-193883D01*
D02*
G37*
G36*
X366535Y-200527D02*
X365833Y-200667D01*
X365238Y-201064D01*
X364840Y-201660D01*
X364700Y-202362D01*
X364840Y-203064D01*
X365238Y-203660D01*
X365833Y-204058D01*
X366535Y-204198D01*
X367238Y-204058D01*
X367833Y-203660D01*
X368231Y-203064D01*
X368371Y-202362D01*
X368231Y-201660D01*
X367833Y-201064D01*
X367238Y-200667D01*
X366535Y-200527D01*
D02*
G37*
G36*
X544291Y-193883D02*
X543589Y-194023D01*
X542994Y-194420D01*
X542596Y-195016D01*
X542456Y-195718D01*
X542596Y-196420D01*
X542784Y-196702D01*
X542596Y-196984D01*
X542456Y-197687D01*
X542596Y-198389D01*
X542784Y-198671D01*
X542596Y-198953D01*
X542456Y-199655D01*
X542596Y-200357D01*
X542784Y-200639D01*
X542596Y-200921D01*
X542456Y-201624D01*
X542596Y-202326D01*
X542994Y-202921D01*
X543589Y-203319D01*
X544291Y-203459D01*
X544994Y-203319D01*
X545496Y-203585D01*
X545548Y-203852D01*
X545946Y-204447D01*
X546542Y-204845D01*
X547244Y-204985D01*
X547946Y-204845D01*
X548542Y-204447D01*
X548940Y-203852D01*
X549079Y-203150D01*
X548940Y-202447D01*
X548542Y-201852D01*
X547946Y-201454D01*
X547244Y-201314D01*
X546542Y-201454D01*
X546040Y-201188D01*
X545987Y-200921D01*
X545798Y-200639D01*
X545987Y-200357D01*
X546127Y-199655D01*
X545987Y-198953D01*
X545798Y-198671D01*
X545987Y-198389D01*
X546127Y-197687D01*
X545987Y-196984D01*
X545798Y-196702D01*
X545987Y-196420D01*
X546127Y-195718D01*
X545987Y-195016D01*
X545589Y-194420D01*
X544994Y-194023D01*
X544291Y-193883D01*
D02*
G37*
G36*
X379921Y-199905D02*
X379219Y-200045D01*
X378624Y-200442D01*
X378226Y-201038D01*
X378146Y-201440D01*
X377975Y-201794D01*
X377621Y-201965D01*
X377219Y-202045D01*
X376624Y-202442D01*
X376226Y-203038D01*
X376086Y-203740D01*
X376226Y-204443D01*
X376624Y-205038D01*
X377219Y-205436D01*
X377921Y-205575D01*
X378624Y-205436D01*
X379219Y-205038D01*
X379617Y-204443D01*
X379697Y-204041D01*
X379868Y-203686D01*
X380222Y-203516D01*
X380624Y-203436D01*
X381219Y-203038D01*
X381617Y-202443D01*
X381756Y-201740D01*
X381617Y-201038D01*
X381219Y-200442D01*
X380624Y-200045D01*
X379921Y-199905D01*
D02*
G37*
G36*
X361417Y-201314D02*
X360715Y-201454D01*
X360120Y-201852D01*
X359722Y-202447D01*
X359582Y-203150D01*
X359722Y-203852D01*
X360120Y-204447D01*
X360715Y-204845D01*
X361007Y-204903D01*
X361075Y-205231D01*
X361060Y-205424D01*
X360513Y-205789D01*
X360116Y-206384D01*
X359976Y-207087D01*
X360116Y-207789D01*
X360513Y-208384D01*
X361109Y-208782D01*
X361811Y-208922D01*
X362513Y-208782D01*
X363109Y-208384D01*
X363507Y-207789D01*
X363646Y-207087D01*
X363507Y-206384D01*
X363109Y-205789D01*
X362513Y-205391D01*
X362221Y-205333D01*
X362153Y-205005D01*
X362168Y-204813D01*
X362715Y-204447D01*
X363113Y-203852D01*
X363253Y-203150D01*
X363113Y-202447D01*
X362715Y-201852D01*
X362120Y-201454D01*
X361417Y-201314D01*
D02*
G37*
G36*
X549213Y-206039D02*
X548510Y-206178D01*
X547915Y-206576D01*
X547517Y-207172D01*
X547377Y-207874D01*
X547517Y-208576D01*
X547915Y-209172D01*
X548510Y-209570D01*
X549213Y-209709D01*
X549915Y-209570D01*
X550510Y-209172D01*
X550908Y-208576D01*
X551048Y-207874D01*
X550908Y-207172D01*
X550510Y-206576D01*
X549915Y-206178D01*
X549213Y-206039D01*
D02*
G37*
G36*
X-3528Y-205543D02*
X-13402D01*
Y-215417D01*
X-3528D01*
Y-205543D01*
D02*
G37*
G36*
X86562Y-209347D02*
X85860Y-209487D01*
X85264Y-209885D01*
X84867Y-210480D01*
X84727Y-211183D01*
X84867Y-211885D01*
X84886Y-211915D01*
X84332Y-212285D01*
X83934Y-212880D01*
X83795Y-213583D01*
X83934Y-214285D01*
X84332Y-214880D01*
X84928Y-215278D01*
X85630Y-215418D01*
X86332Y-215278D01*
X86928Y-214880D01*
X87326Y-214285D01*
X87465Y-213583D01*
X87326Y-212880D01*
X87306Y-212851D01*
X87860Y-212480D01*
X88258Y-211885D01*
X88398Y-211183D01*
X88258Y-210480D01*
X87860Y-209885D01*
X87265Y-209487D01*
X86562Y-209347D01*
D02*
G37*
G36*
X544291Y-213568D02*
X543589Y-213708D01*
X542994Y-214105D01*
X542596Y-214701D01*
X542456Y-215403D01*
X542596Y-216106D01*
X542994Y-216701D01*
X543589Y-217099D01*
X544291Y-217238D01*
X544994Y-217099D01*
X545589Y-216701D01*
X545987Y-216106D01*
X546127Y-215403D01*
X545987Y-214701D01*
X545589Y-214105D01*
X544994Y-213708D01*
X544291Y-213568D01*
D02*
G37*
G36*
X102528Y-209747D02*
X101825Y-209887D01*
X101230Y-210285D01*
X100832Y-210880D01*
X100692Y-211583D01*
X100832Y-212285D01*
X100909Y-212401D01*
X100753Y-212778D01*
X100639Y-212896D01*
X100080Y-213269D01*
X99682Y-213865D01*
X99610Y-214230D01*
X99409Y-214700D01*
X98707Y-214840D01*
X98112Y-215238D01*
X97714Y-215833D01*
X97574Y-216535D01*
X97714Y-217238D01*
X97731Y-217264D01*
X97430Y-217714D01*
X97125Y-217653D01*
X96423Y-217793D01*
X95828Y-218191D01*
X95430Y-218786D01*
X95290Y-219488D01*
X95430Y-220191D01*
X95828Y-220786D01*
X96423Y-221184D01*
X97125Y-221323D01*
X97828Y-221184D01*
X98423Y-220786D01*
X98821Y-220191D01*
X98961Y-219488D01*
X98821Y-218786D01*
X98803Y-218760D01*
X99104Y-218310D01*
X99410Y-218371D01*
X100112Y-218231D01*
X100707Y-217833D01*
X101105Y-217238D01*
X101178Y-216872D01*
X101378Y-216402D01*
X102080Y-216263D01*
X102676Y-215865D01*
X103074Y-215269D01*
X103213Y-214567D01*
X103074Y-213865D01*
X102996Y-213749D01*
X103187Y-213287D01*
X103230Y-213278D01*
X103825Y-212880D01*
X104223Y-212285D01*
X104363Y-211583D01*
X104223Y-210880D01*
X103825Y-210285D01*
X103230Y-209887D01*
X102528Y-209747D01*
D02*
G37*
G36*
X635039Y-214306D02*
X634337Y-214446D01*
X633742Y-214844D01*
X633344Y-215439D01*
X633204Y-216142D01*
X633344Y-216844D01*
X633742Y-217439D01*
X634337Y-217837D01*
X635039Y-217977D01*
X635742Y-217837D01*
X636337Y-217439D01*
X636735Y-216844D01*
X636875Y-216142D01*
X636735Y-215439D01*
X636337Y-214844D01*
X635742Y-214446D01*
X635039Y-214306D01*
D02*
G37*
G36*
X680709Y-215094D02*
X680006Y-215234D01*
X679411Y-215631D01*
X679013Y-216227D01*
X678873Y-216929D01*
X679013Y-217631D01*
X679411Y-218227D01*
X680006Y-218625D01*
X680709Y-218764D01*
X681411Y-218625D01*
X682006Y-218227D01*
X682404Y-217631D01*
X682544Y-216929D01*
X682404Y-216227D01*
X682006Y-215631D01*
X681411Y-215234D01*
X680709Y-215094D01*
D02*
G37*
G36*
X671654Y-215488D02*
X670951Y-215627D01*
X670356Y-216025D01*
X669958Y-216620D01*
X669818Y-217323D01*
X669958Y-218025D01*
X670356Y-218621D01*
X670951Y-219018D01*
X671654Y-219158D01*
X672356Y-219018D01*
X672951Y-218621D01*
X673349Y-218025D01*
X673489Y-217323D01*
X673349Y-216620D01*
X672951Y-216025D01*
X672356Y-215627D01*
X671654Y-215488D01*
D02*
G37*
G36*
X652756Y-216669D02*
X652054Y-216808D01*
X651458Y-217206D01*
X651060Y-217802D01*
X650921Y-218504D01*
X651060Y-219206D01*
X651458Y-219802D01*
X652054Y-220199D01*
X652756Y-220339D01*
X653458Y-220199D01*
X654054Y-219802D01*
X654452Y-219206D01*
X654591Y-218504D01*
X654452Y-217802D01*
X654054Y-217206D01*
X653458Y-216808D01*
X652756Y-216669D01*
D02*
G37*
G36*
X361531Y-221590D02*
X360828Y-221730D01*
X360331Y-222062D01*
X359833Y-221730D01*
X359131Y-221590D01*
X358428Y-221730D01*
X357833Y-222128D01*
X357435Y-222723D01*
X357295Y-223425D01*
X356818Y-223459D01*
X356578Y-223412D01*
X356341Y-223459D01*
X356237Y-222933D01*
X355839Y-222338D01*
X355244Y-221940D01*
X354541Y-221800D01*
X353839Y-221940D01*
X353243Y-222338D01*
X352846Y-222933D01*
X352706Y-223636D01*
X352846Y-224338D01*
X353243Y-224934D01*
X353839Y-225331D01*
X354541Y-225471D01*
X354778Y-225424D01*
X354882Y-225949D01*
X355280Y-226545D01*
X355875Y-226942D01*
X356578Y-227082D01*
X357280Y-226942D01*
X357875Y-226545D01*
X358273Y-225949D01*
X358413Y-225247D01*
X358891Y-225213D01*
X359131Y-225260D01*
X359833Y-225121D01*
X360331Y-224788D01*
X360828Y-225121D01*
X361531Y-225260D01*
X362233Y-225121D01*
X362828Y-224723D01*
X363226Y-224128D01*
X363366Y-223425D01*
X363226Y-222723D01*
X362828Y-222128D01*
X362233Y-221730D01*
X361531Y-221590D01*
D02*
G37*
G36*
X86614Y-219621D02*
X85912Y-219761D01*
X85316Y-220159D01*
X84919Y-220754D01*
X84779Y-221457D01*
X84919Y-222159D01*
X85316Y-222754D01*
X85912Y-223152D01*
X86614Y-223292D01*
X87317Y-223152D01*
X87912Y-222754D01*
X88310Y-222159D01*
X88449Y-221457D01*
X88310Y-220754D01*
X87912Y-220159D01*
X87317Y-219761D01*
X86614Y-219621D01*
D02*
G37*
G36*
X63976D02*
X63274Y-219761D01*
X62679Y-220159D01*
X62281Y-220754D01*
X62141Y-221457D01*
X62281Y-222159D01*
X62679Y-222754D01*
X63274Y-223152D01*
X63976Y-223292D01*
X64679Y-223152D01*
X65274Y-222754D01*
X65672Y-222159D01*
X65812Y-221457D01*
X65672Y-220754D01*
X65274Y-220159D01*
X64679Y-219761D01*
X63976Y-219621D01*
D02*
G37*
G36*
X495669Y-220212D02*
X494967Y-220352D01*
X494372Y-220749D01*
X493974Y-221345D01*
X493834Y-222047D01*
X493974Y-222750D01*
X494372Y-223345D01*
X494967Y-223743D01*
X495669Y-223883D01*
X496372Y-223743D01*
X496967Y-223345D01*
X497365Y-222750D01*
X497505Y-222047D01*
X497365Y-221345D01*
X496967Y-220749D01*
X496372Y-220352D01*
X495669Y-220212D01*
D02*
G37*
G36*
X500394Y-220999D02*
X499691Y-221139D01*
X499096Y-221537D01*
X498698Y-222132D01*
X498558Y-222835D01*
X498698Y-223537D01*
X499096Y-224132D01*
X499691Y-224530D01*
X500394Y-224670D01*
X501096Y-224530D01*
X501691Y-224132D01*
X502089Y-223537D01*
X502229Y-222835D01*
X502089Y-222132D01*
X501691Y-221537D01*
X501096Y-221139D01*
X500394Y-220999D01*
D02*
G37*
G36*
X544294Y-222412D02*
X543592Y-222552D01*
X542997Y-222950D01*
X542599Y-223545D01*
X542459Y-224248D01*
X542587Y-224892D01*
X542573Y-224895D01*
X541978Y-225293D01*
X541580Y-225889D01*
X541440Y-226591D01*
X541580Y-227293D01*
X541978Y-227889D01*
X542573Y-228287D01*
X543276Y-228426D01*
X543978Y-228287D01*
X544573Y-227889D01*
X544971Y-227293D01*
X545111Y-226591D01*
X544983Y-225946D01*
X544997Y-225943D01*
X545592Y-225545D01*
X545990Y-224950D01*
X546130Y-224248D01*
X545990Y-223545D01*
X545592Y-222950D01*
X544997Y-222552D01*
X544294Y-222412D01*
D02*
G37*
G36*
X572441Y-225330D02*
X571739Y-225470D01*
X571143Y-225868D01*
X570745Y-226463D01*
X570606Y-227165D01*
X570745Y-227868D01*
X571143Y-228463D01*
X571739Y-228861D01*
X572441Y-229001D01*
X573143Y-228861D01*
X573739Y-228463D01*
X574136Y-227868D01*
X574276Y-227165D01*
X574136Y-226463D01*
X573739Y-225868D01*
X573143Y-225470D01*
X572441Y-225330D01*
D02*
G37*
G36*
X86614Y-225527D02*
X85912Y-225667D01*
X85316Y-226064D01*
X84919Y-226660D01*
X84779Y-227362D01*
X84919Y-228064D01*
X85316Y-228660D01*
X85912Y-229058D01*
X86614Y-229198D01*
X87317Y-229058D01*
X87912Y-228660D01*
X88310Y-228064D01*
X88449Y-227362D01*
X88310Y-226660D01*
X87912Y-226064D01*
X87317Y-225667D01*
X86614Y-225527D01*
D02*
G37*
G36*
X314503Y-223344D02*
X313800Y-223484D01*
X313205Y-223882D01*
X312807Y-224477D01*
X312667Y-225180D01*
X312807Y-225882D01*
X313205Y-226477D01*
X312987Y-226933D01*
X312721Y-227330D01*
X312581Y-228033D01*
X312721Y-228735D01*
X313119Y-229330D01*
X313343Y-229480D01*
Y-230082D01*
X313326Y-230093D01*
X312928Y-230689D01*
X312788Y-231391D01*
X312928Y-232093D01*
X313326Y-232689D01*
X313921Y-233086D01*
X314623Y-233226D01*
X315326Y-233086D01*
X315921Y-232689D01*
X316319Y-232093D01*
X316459Y-231391D01*
X316319Y-230689D01*
X315921Y-230093D01*
X315697Y-229943D01*
Y-229342D01*
X315714Y-229330D01*
X316112Y-228735D01*
X316252Y-228033D01*
X316112Y-227330D01*
X315714Y-226735D01*
X315933Y-226279D01*
X316198Y-225882D01*
X316338Y-225180D01*
X316198Y-224477D01*
X315800Y-223882D01*
X315205Y-223484D01*
X314503Y-223344D01*
D02*
G37*
G36*
X361652Y-233369D02*
X360950Y-233509D01*
X360428Y-233857D01*
X359954Y-233541D01*
X359252Y-233401D01*
X358550Y-233541D01*
X358052Y-233873D01*
X357554Y-233541D01*
X356852Y-233401D01*
X356150Y-233541D01*
X355652Y-233873D01*
X355154Y-233541D01*
X354452Y-233401D01*
X353750Y-233541D01*
X353154Y-233939D01*
X352756Y-234534D01*
X352617Y-235236D01*
X352756Y-235939D01*
X353154Y-236534D01*
X353750Y-236932D01*
X354452Y-237071D01*
X355154Y-236932D01*
X355652Y-236599D01*
X356150Y-236932D01*
X356852Y-237071D01*
X357554Y-236932D01*
X358052Y-236599D01*
X358550Y-236932D01*
X359252Y-237071D01*
X359954Y-236932D01*
X360475Y-236583D01*
X360950Y-236900D01*
X361652Y-237040D01*
X362354Y-236900D01*
X362950Y-236502D01*
X363348Y-235907D01*
X363487Y-235205D01*
X363348Y-234502D01*
X362950Y-233907D01*
X362354Y-233509D01*
X361652Y-233369D01*
D02*
G37*
G36*
X82677Y-230448D02*
X81975Y-230588D01*
X81379Y-230986D01*
X80982Y-231581D01*
X80842Y-232283D01*
X80982Y-232986D01*
X81379Y-233581D01*
X81975Y-233979D01*
X82677Y-234119D01*
X83380Y-233979D01*
X83975Y-233581D01*
X84373Y-232986D01*
X84512Y-232283D01*
X84373Y-231581D01*
X83975Y-230986D01*
X83380Y-230588D01*
X82677Y-230448D01*
D02*
G37*
G36*
X75787D02*
X75085Y-230588D01*
X74490Y-230986D01*
X74092Y-231581D01*
X73952Y-232283D01*
X74092Y-232986D01*
X74490Y-233581D01*
X75085Y-233979D01*
X75787Y-234119D01*
X76490Y-233979D01*
X77085Y-233581D01*
X77483Y-232986D01*
X77623Y-232283D01*
X77483Y-231581D01*
X77085Y-230986D01*
X76490Y-230588D01*
X75787Y-230448D01*
D02*
G37*
G36*
X544291Y-231433D02*
X543589Y-231572D01*
X542994Y-231970D01*
X542596Y-232565D01*
X542456Y-233268D01*
X542596Y-233970D01*
X542994Y-234565D01*
X543589Y-234963D01*
X544291Y-235103D01*
X544994Y-234963D01*
X545589Y-234565D01*
X545987Y-233970D01*
X546127Y-233268D01*
X545987Y-232565D01*
X545589Y-231970D01*
X544994Y-231572D01*
X544291Y-231433D01*
D02*
G37*
G36*
X323819Y-225527D02*
X323117Y-225667D01*
X322521Y-226064D01*
X322123Y-226660D01*
X321984Y-227362D01*
X322123Y-228064D01*
X322521Y-228660D01*
X323117Y-229058D01*
X323207Y-229076D01*
Y-229586D01*
X323117Y-229604D01*
X322521Y-230001D01*
X322123Y-230597D01*
X321984Y-231299D01*
X322123Y-232001D01*
X322521Y-232597D01*
X323117Y-232995D01*
X323548Y-233081D01*
X323952Y-233362D01*
X324092Y-234065D01*
X324490Y-234660D01*
X325085Y-235058D01*
X325787Y-235197D01*
X326490Y-235058D01*
X327085Y-234660D01*
X327483Y-234065D01*
X327623Y-233362D01*
X327483Y-232660D01*
X327085Y-232065D01*
X326490Y-231667D01*
X326241Y-231617D01*
Y-231107D01*
X326490Y-231058D01*
X327085Y-230660D01*
X327483Y-230065D01*
X327623Y-229362D01*
X327483Y-228660D01*
X327085Y-228064D01*
X326490Y-227667D01*
X326118Y-227593D01*
X325736Y-227403D01*
X325593Y-227056D01*
X325515Y-226660D01*
X325117Y-226064D01*
X324521Y-225667D01*
X323819Y-225527D01*
D02*
G37*
G36*
X288583Y-223755D02*
X287880Y-223895D01*
X287285Y-224293D01*
X286887Y-224888D01*
X286747Y-225590D01*
X286887Y-226293D01*
X287163Y-226705D01*
X287285Y-226888D01*
X287053Y-227334D01*
X286891Y-227442D01*
X286493Y-228038D01*
X286354Y-228740D01*
X286493Y-229443D01*
X286813Y-229921D01*
X286493Y-230400D01*
X286354Y-231102D01*
X286493Y-231805D01*
X286752Y-232191D01*
X286362Y-232775D01*
X286222Y-233478D01*
X286362Y-234180D01*
X286759Y-234776D01*
X287355Y-235173D01*
X288057Y-235313D01*
X288759Y-235173D01*
X289355Y-234776D01*
X289753Y-234180D01*
X289892Y-233478D01*
X289753Y-232775D01*
X289494Y-232389D01*
X289884Y-231805D01*
X290024Y-231102D01*
X289884Y-230400D01*
X289565Y-229921D01*
X289884Y-229443D01*
X290024Y-228740D01*
X289884Y-228038D01*
X289609Y-227625D01*
X289487Y-227442D01*
X289719Y-226996D01*
X289880Y-226888D01*
X290278Y-226293D01*
X290418Y-225590D01*
X290278Y-224888D01*
X289880Y-224293D01*
X289285Y-223895D01*
X288583Y-223755D01*
D02*
G37*
G36*
X608661Y-234385D02*
X607959Y-234525D01*
X607364Y-234923D01*
X606966Y-235518D01*
X606826Y-236221D01*
X606966Y-236923D01*
X607364Y-237518D01*
X607959Y-237916D01*
X608661Y-238056D01*
X609364Y-237916D01*
X609959Y-237518D01*
X610357Y-236923D01*
X610497Y-236221D01*
X610357Y-235518D01*
X609959Y-234923D01*
X609364Y-234525D01*
X608661Y-234385D01*
D02*
G37*
G36*
X78740Y-236206D02*
X78038Y-236345D01*
X77442Y-236743D01*
X77045Y-237339D01*
X76905Y-238041D01*
X77045Y-238743D01*
X77442Y-239339D01*
X78038Y-239737D01*
X78740Y-239876D01*
X79443Y-239737D01*
X80038Y-239339D01*
X80436Y-238743D01*
X80575Y-238041D01*
X80436Y-237339D01*
X80038Y-236743D01*
X79443Y-236345D01*
X78740Y-236206D01*
D02*
G37*
G36*
X637008Y-236747D02*
X636306Y-236887D01*
X635710Y-237285D01*
X635312Y-237880D01*
X635173Y-238583D01*
X635312Y-239285D01*
X635710Y-239880D01*
X636306Y-240278D01*
X637008Y-240418D01*
X637710Y-240278D01*
X638306Y-239880D01*
X638703Y-239285D01*
X638843Y-238583D01*
X638703Y-237880D01*
X638306Y-237285D01*
X637710Y-236887D01*
X637008Y-236747D01*
D02*
G37*
G36*
X-23622Y-227495D02*
X-24324Y-227635D01*
X-24920Y-228033D01*
X-25318Y-228628D01*
X-25457Y-229331D01*
X-25318Y-230033D01*
X-24920Y-230628D01*
X-24324Y-231026D01*
X-24234Y-231044D01*
Y-231554D01*
X-24324Y-231572D01*
X-24920Y-231970D01*
X-25318Y-232565D01*
X-25457Y-233268D01*
X-25318Y-233970D01*
X-24920Y-234565D01*
X-24324Y-234963D01*
X-24234Y-234981D01*
Y-235491D01*
X-24324Y-235509D01*
X-24920Y-235907D01*
X-25318Y-236502D01*
X-25457Y-237205D01*
X-25318Y-237907D01*
X-24920Y-238502D01*
X-24324Y-238900D01*
X-24234Y-238918D01*
Y-239428D01*
X-24324Y-239446D01*
X-24920Y-239844D01*
X-25318Y-240439D01*
X-25457Y-241142D01*
X-25318Y-241844D01*
X-24920Y-242439D01*
X-24324Y-242837D01*
X-23622Y-242977D01*
X-22920Y-242837D01*
X-22324Y-242439D01*
X-21926Y-241844D01*
X-21787Y-241142D01*
X-21926Y-240439D01*
X-22324Y-239844D01*
X-22920Y-239446D01*
X-23010Y-239428D01*
Y-238918D01*
X-22920Y-238900D01*
X-22324Y-238502D01*
X-21926Y-237907D01*
X-21787Y-237205D01*
X-21926Y-236502D01*
X-22324Y-235907D01*
X-22920Y-235509D01*
X-23010Y-235491D01*
Y-234981D01*
X-22920Y-234963D01*
X-22324Y-234565D01*
X-21926Y-233970D01*
X-21787Y-233268D01*
X-21926Y-232565D01*
X-22324Y-231970D01*
X-22920Y-231572D01*
X-23010Y-231554D01*
Y-231044D01*
X-22920Y-231026D01*
X-22324Y-230628D01*
X-21926Y-230033D01*
X-21787Y-229331D01*
X-21926Y-228628D01*
X-22324Y-228033D01*
X-22920Y-227635D01*
X-23622Y-227495D01*
D02*
G37*
G36*
X608661Y-240291D02*
X607959Y-240430D01*
X607364Y-240828D01*
X606966Y-241424D01*
X606826Y-242126D01*
X606966Y-242828D01*
X607364Y-243424D01*
X607959Y-243822D01*
X608661Y-243961D01*
X609364Y-243822D01*
X609959Y-243424D01*
X610357Y-242828D01*
X610497Y-242126D01*
X610357Y-241424D01*
X609959Y-240828D01*
X609364Y-240430D01*
X608661Y-240291D01*
D02*
G37*
G36*
X590551Y-240684D02*
X589849Y-240824D01*
X589254Y-241222D01*
X588856Y-241817D01*
X588716Y-242520D01*
X588856Y-243222D01*
X589254Y-243817D01*
X589849Y-244215D01*
X590551Y-244355D01*
X591254Y-244215D01*
X591849Y-243817D01*
X592247Y-243222D01*
X592386Y-242520D01*
X592247Y-241817D01*
X591849Y-241222D01*
X591254Y-240824D01*
X590551Y-240684D01*
D02*
G37*
G36*
X323850Y-235369D02*
X323148Y-235509D01*
X322553Y-235907D01*
X322155Y-236502D01*
X322015Y-237205D01*
X322155Y-237907D01*
X322553Y-238502D01*
X323148Y-238900D01*
X323318Y-238934D01*
Y-239444D01*
X323148Y-239478D01*
X322553Y-239876D01*
X322155Y-240471D01*
X322015Y-241173D01*
X322155Y-241876D01*
X322553Y-242471D01*
X323148Y-242869D01*
X323850Y-243008D01*
X324008Y-243487D01*
X324092Y-243907D01*
X324490Y-244502D01*
X325085Y-244900D01*
X325787Y-245040D01*
X326490Y-244900D01*
X327085Y-244502D01*
X327483Y-243907D01*
X327623Y-243205D01*
X327483Y-242502D01*
X327085Y-241907D01*
X326490Y-241509D01*
X326241Y-241460D01*
Y-240950D01*
X326490Y-240900D01*
X327085Y-240502D01*
X327483Y-239907D01*
X327623Y-239205D01*
X327483Y-238502D01*
X327085Y-237907D01*
X326490Y-237509D01*
X326148Y-237441D01*
X325740Y-237233D01*
X325623Y-236892D01*
X325546Y-236502D01*
X325148Y-235907D01*
X324553Y-235509D01*
X323850Y-235369D01*
D02*
G37*
G36*
X314658Y-242939D02*
X313955Y-243079D01*
X313360Y-243477D01*
X312962Y-244072D01*
X312823Y-244775D01*
X312962Y-245477D01*
X313360Y-246073D01*
X313955Y-246470D01*
X314658Y-246610D01*
X315360Y-246470D01*
X315955Y-246073D01*
X316353Y-245477D01*
X316493Y-244775D01*
X316353Y-244072D01*
X315955Y-243477D01*
X315360Y-243079D01*
X314658Y-242939D01*
D02*
G37*
G36*
X288057Y-243260D02*
X287355Y-243399D01*
X286759Y-243797D01*
X286362Y-244393D01*
X286222Y-245095D01*
X286362Y-245797D01*
X286759Y-246393D01*
X286826Y-246437D01*
X286493Y-246936D01*
X286354Y-247638D01*
X286493Y-248340D01*
X286891Y-248936D01*
X287487Y-249333D01*
X288189Y-249473D01*
X288891Y-249333D01*
X289487Y-248936D01*
X289884Y-248340D01*
X290024Y-247638D01*
X289884Y-246936D01*
X289487Y-246340D01*
X289420Y-246295D01*
X289753Y-245797D01*
X289893Y-245095D01*
X289753Y-244393D01*
X289355Y-243797D01*
X288759Y-243399D01*
X288057Y-243260D01*
D02*
G37*
G36*
X585039Y-247771D02*
X584337Y-247911D01*
X583742Y-248309D01*
X583344Y-248904D01*
X583204Y-249606D01*
X583344Y-250309D01*
X583742Y-250904D01*
X584337Y-251302D01*
X585039Y-251442D01*
X585742Y-251302D01*
X586337Y-250904D01*
X586735Y-250309D01*
X586875Y-249606D01*
X586735Y-248904D01*
X586337Y-248309D01*
X585742Y-247911D01*
X585039Y-247771D01*
D02*
G37*
G36*
X360204Y-251149D02*
X359502Y-251289D01*
X358907Y-251687D01*
X358509Y-252282D01*
X358369Y-252984D01*
X358509Y-253687D01*
X358907Y-254282D01*
X359502Y-254680D01*
X360204Y-254819D01*
X360907Y-254680D01*
X361502Y-254282D01*
X361900Y-253687D01*
X362040Y-252984D01*
X361900Y-252282D01*
X361502Y-251687D01*
X360907Y-251289D01*
X360204Y-251149D01*
D02*
G37*
G36*
X585433Y-252102D02*
X584731Y-252241D01*
X584135Y-252639D01*
X583738Y-253235D01*
X583598Y-253937D01*
X583738Y-254639D01*
X584135Y-255235D01*
X584395Y-255408D01*
Y-256009D01*
X584135Y-256183D01*
X583738Y-256778D01*
X583719Y-256869D01*
X583210D01*
X583192Y-256778D01*
X582794Y-256183D01*
X582198Y-255785D01*
X581496Y-255645D01*
X580794Y-255785D01*
X580198Y-256183D01*
X580025Y-256442D01*
X579424D01*
X579250Y-256183D01*
X578655Y-255785D01*
X577953Y-255645D01*
X577250Y-255785D01*
X576655Y-256183D01*
X576257Y-256778D01*
X576118Y-257480D01*
X576257Y-258183D01*
X576655Y-258778D01*
X577250Y-259176D01*
X577953Y-259316D01*
X578655Y-259176D01*
X579250Y-258778D01*
X579424Y-258519D01*
X580025D01*
X580198Y-258778D01*
X580794Y-259176D01*
X581496Y-259316D01*
X582198Y-259176D01*
X582794Y-258778D01*
X583192Y-258183D01*
X583210Y-258092D01*
X583719D01*
X583738Y-258183D01*
X584135Y-258778D01*
X584731Y-259176D01*
X585433Y-259316D01*
X586135Y-259176D01*
X586731Y-258778D01*
X587129Y-258183D01*
X587268Y-257480D01*
X587129Y-256778D01*
X586731Y-256183D01*
X586472Y-256009D01*
Y-255408D01*
X586731Y-255235D01*
X587129Y-254639D01*
X587268Y-253937D01*
X587129Y-253235D01*
X586731Y-252639D01*
X586135Y-252241D01*
X585433Y-252102D01*
D02*
G37*
G36*
X563386Y-256039D02*
X562683Y-256178D01*
X562088Y-256576D01*
X561690Y-257172D01*
X561551Y-257874D01*
X561690Y-258576D01*
X562088Y-259172D01*
X562683Y-259570D01*
X563386Y-259709D01*
X564088Y-259570D01*
X564684Y-259172D01*
X565081Y-258576D01*
X565221Y-257874D01*
X565081Y-257172D01*
X564684Y-256576D01*
X564088Y-256178D01*
X563386Y-256039D01*
D02*
G37*
G36*
X572441Y-256433D02*
X571739Y-256572D01*
X571143Y-256970D01*
X570745Y-257565D01*
X570606Y-258268D01*
X570745Y-258970D01*
X571143Y-259565D01*
X571739Y-259963D01*
X572441Y-260103D01*
X573143Y-259963D01*
X573739Y-259565D01*
X574136Y-258970D01*
X574276Y-258268D01*
X574136Y-257565D01*
X573739Y-256970D01*
X573143Y-256572D01*
X572441Y-256433D01*
D02*
G37*
G36*
X556628Y-256207D02*
X555925Y-256347D01*
X555330Y-256744D01*
X554932Y-257340D01*
X554792Y-258042D01*
X554932Y-258744D01*
X555330Y-259340D01*
X555693Y-259582D01*
X555784Y-260093D01*
X555751Y-260176D01*
X555391Y-260715D01*
X555251Y-261417D01*
X555391Y-262120D01*
X555789Y-262715D01*
X556384Y-263113D01*
X557087Y-263253D01*
X557789Y-263113D01*
X558384Y-262715D01*
X558782Y-262120D01*
X558922Y-261417D01*
X558782Y-260715D01*
X558384Y-260120D01*
X558021Y-259877D01*
X557930Y-259366D01*
X557964Y-259283D01*
X558323Y-258744D01*
X558463Y-258042D01*
X558323Y-257340D01*
X557926Y-256744D01*
X557330Y-256347D01*
X556628Y-256207D01*
D02*
G37*
G36*
X120079Y-261551D02*
X119376Y-261690D01*
X118781Y-262088D01*
X118383Y-262684D01*
X118244Y-263386D01*
X118383Y-264088D01*
X118781Y-264684D01*
X119376Y-265081D01*
X120079Y-265221D01*
X120781Y-265081D01*
X121377Y-264684D01*
X121774Y-264088D01*
X121914Y-263386D01*
X121774Y-262684D01*
X121377Y-262088D01*
X120781Y-261690D01*
X120079Y-261551D01*
D02*
G37*
G36*
X106299Y-261796D02*
X105597Y-261936D01*
X105001Y-262334D01*
X104604Y-262929D01*
X104464Y-263632D01*
X104604Y-264334D01*
X105001Y-264929D01*
X105597Y-265327D01*
X106299Y-265467D01*
X107001Y-265327D01*
X107597Y-264929D01*
X107995Y-264334D01*
X108134Y-263632D01*
X107995Y-262929D01*
X107597Y-262334D01*
X107001Y-261936D01*
X106299Y-261796D01*
D02*
G37*
G36*
X85630Y-261944D02*
X84928Y-262084D01*
X84332Y-262482D01*
X83934Y-263077D01*
X83795Y-263779D01*
X83934Y-264482D01*
X84267Y-264980D01*
X83934Y-265477D01*
X83795Y-266179D01*
X83934Y-266882D01*
X84332Y-267477D01*
X84928Y-267875D01*
X85630Y-268015D01*
X86332Y-267875D01*
X86928Y-267477D01*
X87326Y-266882D01*
X87465Y-266179D01*
X87326Y-265477D01*
X86993Y-264980D01*
X87326Y-264482D01*
X87465Y-263779D01*
X87326Y-263077D01*
X86928Y-262482D01*
X86332Y-262084D01*
X85630Y-261944D01*
D02*
G37*
G36*
X588189Y-261551D02*
X587487Y-261690D01*
X586891Y-262088D01*
X586493Y-262684D01*
X586354Y-263386D01*
X586493Y-264088D01*
X586891Y-264684D01*
X587487Y-265081D01*
X588189Y-265221D01*
X588736Y-265112D01*
X589064Y-265522D01*
X588856Y-265833D01*
X588716Y-266535D01*
X588856Y-267238D01*
X589254Y-267833D01*
X589849Y-268231D01*
X590551Y-268371D01*
X591254Y-268231D01*
X591849Y-267833D01*
X592247Y-267238D01*
X592386Y-266535D01*
X592247Y-265833D01*
X591849Y-265238D01*
X591254Y-264840D01*
X590551Y-264700D01*
X590004Y-264809D01*
X589677Y-264399D01*
X589885Y-264088D01*
X590024Y-263386D01*
X589885Y-262684D01*
X589487Y-262088D01*
X588891Y-261690D01*
X588189Y-261551D01*
D02*
G37*
G36*
X-3528Y-258693D02*
X-13402D01*
Y-268567D01*
X-3528D01*
Y-258693D01*
D02*
G37*
G36*
X512402Y-260123D02*
X511699Y-260263D01*
X511104Y-260661D01*
X510706Y-261256D01*
X510566Y-261958D01*
X510706Y-262661D01*
X511104Y-263256D01*
X511144Y-263283D01*
Y-263783D01*
X511104Y-263810D01*
X510706Y-264406D01*
X510566Y-265108D01*
X510706Y-265810D01*
X511037Y-266305D01*
X511245Y-266767D01*
X510847Y-267363D01*
X510708Y-268065D01*
X510847Y-268767D01*
X511236Y-269349D01*
X510962Y-269760D01*
X510822Y-270462D01*
X510962Y-271165D01*
X511360Y-271760D01*
X511955Y-272158D01*
X512657Y-272298D01*
X513360Y-272158D01*
X513955Y-271760D01*
X514353Y-271165D01*
X514493Y-270462D01*
X514353Y-269760D01*
X513964Y-269178D01*
X514239Y-268767D01*
X514378Y-268065D01*
X514239Y-267363D01*
X513908Y-266868D01*
X513699Y-266406D01*
X514097Y-265810D01*
X514237Y-265108D01*
X514097Y-264406D01*
X513699Y-263810D01*
X513659Y-263783D01*
Y-263283D01*
X513699Y-263256D01*
X514097Y-262661D01*
X514237Y-261958D01*
X514097Y-261256D01*
X513699Y-260661D01*
X513104Y-260263D01*
X512402Y-260123D01*
D02*
G37*
G36*
X545276Y-269031D02*
X544573Y-269171D01*
X543978Y-269568D01*
X543580Y-270164D01*
X543440Y-270866D01*
X543580Y-271568D01*
X543978Y-272164D01*
X544573Y-272562D01*
X545276Y-272701D01*
X545978Y-272562D01*
X546573Y-272164D01*
X546971Y-271568D01*
X547111Y-270866D01*
X546971Y-270164D01*
X546573Y-269568D01*
X545978Y-269171D01*
X545276Y-269031D01*
D02*
G37*
G36*
X325984Y-270606D02*
X325282Y-270745D01*
X324687Y-271143D01*
X324289Y-271739D01*
X324149Y-272441D01*
X324289Y-273143D01*
X324687Y-273739D01*
X325282Y-274136D01*
X325984Y-274276D01*
X326687Y-274136D01*
X327282Y-273739D01*
X327680Y-273143D01*
X327819Y-272441D01*
X327680Y-271739D01*
X327282Y-271143D01*
X326687Y-270745D01*
X325984Y-270606D01*
D02*
G37*
G36*
X360236Y-260350D02*
X359534Y-260490D01*
X358939Y-260888D01*
X358541Y-261484D01*
X358401Y-262186D01*
X358541Y-262888D01*
X358939Y-263484D01*
X359534Y-263881D01*
X359783Y-263931D01*
Y-264441D01*
X359534Y-264490D01*
X358939Y-264888D01*
X358541Y-265483D01*
X358401Y-266186D01*
X358541Y-266888D01*
X358873Y-267386D01*
X358541Y-267883D01*
X358401Y-268586D01*
X358541Y-269288D01*
X358939Y-269883D01*
X359534Y-270281D01*
X359542Y-270283D01*
Y-270793D01*
X359534Y-270794D01*
X358939Y-271192D01*
X358541Y-271787D01*
X358401Y-272490D01*
X358541Y-273192D01*
X358939Y-273787D01*
X359534Y-274185D01*
X360236Y-274325D01*
X360939Y-274185D01*
X361534Y-273787D01*
X361932Y-273192D01*
X362071Y-272490D01*
X361932Y-271787D01*
X361534Y-271192D01*
X360939Y-270794D01*
X360931Y-270793D01*
Y-270283D01*
X360939Y-270281D01*
X361534Y-269883D01*
X361932Y-269288D01*
X362071Y-268586D01*
X361932Y-267883D01*
X361599Y-267386D01*
X361932Y-266888D01*
X362071Y-266186D01*
X361932Y-265483D01*
X361534Y-264888D01*
X360939Y-264490D01*
X360689Y-264441D01*
Y-263931D01*
X360939Y-263881D01*
X361534Y-263484D01*
X361932Y-262888D01*
X362071Y-262186D01*
X361932Y-261484D01*
X361534Y-260888D01*
X360939Y-260490D01*
X360236Y-260350D01*
D02*
G37*
G36*
X340904Y-271286D02*
X340092Y-271448D01*
X339403Y-271908D01*
X338942Y-272597D01*
X338780Y-273410D01*
X338942Y-274223D01*
X339403Y-274912D01*
X340092Y-275372D01*
X340904Y-275534D01*
X341717Y-275372D01*
X342406Y-274912D01*
X342866Y-274223D01*
X343028Y-273410D01*
X342866Y-272597D01*
X342406Y-271908D01*
X341717Y-271448D01*
X340904Y-271286D01*
D02*
G37*
G36*
X528395Y-271296D02*
X527583Y-271458D01*
X526894Y-271918D01*
X526433Y-272607D01*
X526271Y-273420D01*
X526433Y-274233D01*
X526894Y-274921D01*
X527583Y-275382D01*
X528395Y-275544D01*
X529208Y-275382D01*
X529897Y-274921D01*
X530358Y-274233D01*
X530519Y-273420D01*
X530358Y-272607D01*
X529897Y-271918D01*
X529208Y-271458D01*
X528395Y-271296D01*
D02*
G37*
G36*
X651575Y-273362D02*
X650873Y-273501D01*
X650277Y-273899D01*
X649879Y-274495D01*
X649740Y-275197D01*
X649879Y-275899D01*
X650277Y-276495D01*
X650873Y-276892D01*
X651575Y-277032D01*
X652277Y-276892D01*
X652873Y-276495D01*
X653270Y-275899D01*
X653410Y-275197D01*
X653270Y-274495D01*
X652873Y-273899D01*
X652277Y-273501D01*
X651575Y-273362D01*
D02*
G37*
G36*
X545276D02*
X544573Y-273501D01*
X543978Y-273899D01*
X543580Y-274495D01*
X543440Y-275197D01*
X543580Y-275899D01*
X543978Y-276495D01*
X544573Y-276892D01*
X545276Y-277032D01*
X545978Y-276892D01*
X546573Y-276495D01*
X546971Y-275899D01*
X547111Y-275197D01*
X546971Y-274495D01*
X546573Y-273899D01*
X545978Y-273501D01*
X545276Y-273362D01*
D02*
G37*
G36*
X87598Y-273755D02*
X86896Y-273895D01*
X86301Y-274293D01*
X85903Y-274888D01*
X85763Y-275590D01*
X85903Y-276293D01*
X86301Y-276888D01*
X86896Y-277286D01*
X87598Y-277426D01*
X88301Y-277286D01*
X88896Y-276888D01*
X89294Y-276293D01*
X89434Y-275590D01*
X89294Y-274888D01*
X88896Y-274293D01*
X88301Y-273895D01*
X87598Y-273755D01*
D02*
G37*
G36*
X63976D02*
X63274Y-273895D01*
X62679Y-274293D01*
X62281Y-274888D01*
X62141Y-275590D01*
X62281Y-276293D01*
X62679Y-276888D01*
X63274Y-277286D01*
X63976Y-277426D01*
X64679Y-277286D01*
X65274Y-276888D01*
X65672Y-276293D01*
X65812Y-275590D01*
X65672Y-274888D01*
X65274Y-274293D01*
X64679Y-273895D01*
X63976Y-273755D01*
D02*
G37*
G36*
X630577Y-276166D02*
X629874Y-276306D01*
X629279Y-276704D01*
X628881Y-277299D01*
X628741Y-278001D01*
X628881Y-278704D01*
X629279Y-279299D01*
X629874Y-279697D01*
X630577Y-279837D01*
X631279Y-279697D01*
X631874Y-279299D01*
X632272Y-278704D01*
X632412Y-278001D01*
X632272Y-277299D01*
X631874Y-276704D01*
X631279Y-276306D01*
X630577Y-276166D01*
D02*
G37*
G36*
X657087Y-277692D02*
X656384Y-277832D01*
X655789Y-278230D01*
X655391Y-278825D01*
X655251Y-279528D01*
X655391Y-280230D01*
X655789Y-280825D01*
X656384Y-281223D01*
X657087Y-281363D01*
X657789Y-281223D01*
X658384Y-280825D01*
X658782Y-280230D01*
X658922Y-279528D01*
X658782Y-278825D01*
X658384Y-278230D01*
X657789Y-277832D01*
X657087Y-277692D01*
D02*
G37*
G36*
X648819Y-276905D02*
X648117Y-277045D01*
X647521Y-277442D01*
X647123Y-278038D01*
X646984Y-278740D01*
X647123Y-279443D01*
X647521Y-280038D01*
X648117Y-280436D01*
X648819Y-280575D01*
X649521Y-280436D01*
X650117Y-280038D01*
X650118Y-280035D01*
X650649Y-280141D01*
X650667Y-280230D01*
X651064Y-280825D01*
X651660Y-281223D01*
X652362Y-281363D01*
X653064Y-281223D01*
X653660Y-280825D01*
X654058Y-280230D01*
X654198Y-279528D01*
X654058Y-278825D01*
X653660Y-278230D01*
X653064Y-277832D01*
X652362Y-277692D01*
X651660Y-277832D01*
X651064Y-278230D01*
X651063Y-278232D01*
X650532Y-278127D01*
X650515Y-278038D01*
X650117Y-277442D01*
X649521Y-277045D01*
X648819Y-276905D01*
D02*
G37*
G36*
X650000Y-282023D02*
X649298Y-282163D01*
X648702Y-282561D01*
X648529Y-282820D01*
X647928D01*
X647754Y-282561D01*
X647159Y-282163D01*
X646457Y-282023D01*
X645754Y-282163D01*
X645159Y-282561D01*
X644761Y-283156D01*
X644621Y-283858D01*
X644761Y-284561D01*
X645159Y-285156D01*
X645754Y-285554D01*
X646457Y-285694D01*
X647159Y-285554D01*
X647754Y-285156D01*
X647928Y-284897D01*
X648529D01*
X648702Y-285156D01*
X649298Y-285554D01*
X650000Y-285694D01*
X650702Y-285554D01*
X651298Y-285156D01*
X651696Y-284561D01*
X651835Y-283858D01*
X651696Y-283156D01*
X651298Y-282561D01*
X650702Y-282163D01*
X650000Y-282023D01*
D02*
G37*
G36*
X87598Y-279661D02*
X86896Y-279801D01*
X86301Y-280198D01*
X85903Y-280794D01*
X85763Y-281496D01*
X85903Y-282198D01*
X86301Y-282794D01*
X86896Y-283192D01*
X87598Y-283331D01*
X88301Y-283192D01*
X88896Y-282794D01*
X89294Y-282198D01*
X89434Y-281496D01*
X89294Y-280794D01*
X88896Y-280198D01*
X88301Y-279801D01*
X87598Y-279661D01*
D02*
G37*
G36*
X26575Y-281629D02*
X25872Y-281769D01*
X25277Y-282167D01*
X24879Y-282762D01*
X24739Y-283465D01*
X24879Y-284167D01*
X25277Y-284762D01*
X25872Y-285160D01*
X26575Y-285300D01*
X27277Y-285160D01*
X27872Y-284762D01*
X28270Y-284167D01*
X28410Y-283465D01*
X28270Y-282762D01*
X27872Y-282167D01*
X27277Y-281769D01*
X26575Y-281629D01*
D02*
G37*
G36*
X654331Y-282023D02*
X653628Y-282163D01*
X653033Y-282561D01*
X652635Y-283156D01*
X652495Y-283858D01*
X652635Y-284561D01*
X653033Y-285156D01*
X653628Y-285554D01*
X654331Y-285694D01*
X655033Y-285554D01*
X655628Y-285156D01*
X656026Y-284561D01*
X656166Y-283858D01*
X656026Y-283156D01*
X655628Y-282561D01*
X655033Y-282163D01*
X654331Y-282023D01*
D02*
G37*
G36*
X75787Y-283598D02*
X75085Y-283737D01*
X74490Y-284135D01*
X74092Y-284731D01*
X73952Y-285433D01*
X74092Y-286135D01*
X74490Y-286731D01*
X75085Y-287129D01*
X75787Y-287268D01*
X76490Y-287129D01*
X77085Y-286731D01*
X77483Y-286135D01*
X77623Y-285433D01*
X77483Y-284731D01*
X77085Y-284135D01*
X76490Y-283737D01*
X75787Y-283598D01*
D02*
G37*
G36*
X569548Y-285388D02*
X568845Y-285528D01*
X568250Y-285926D01*
X567852Y-286521D01*
X567712Y-287223D01*
X567852Y-287926D01*
X568250Y-288521D01*
X568845Y-288919D01*
X569548Y-289058D01*
X570250Y-288919D01*
X570845Y-288521D01*
X571243Y-287926D01*
X571383Y-287223D01*
X571243Y-286521D01*
X570845Y-285926D01*
X570250Y-285528D01*
X569548Y-285388D01*
D02*
G37*
G36*
X544909Y-285601D02*
X544207Y-285741D01*
X543611Y-286139D01*
X543214Y-286734D01*
X543074Y-287437D01*
X543214Y-288139D01*
X543611Y-288734D01*
X544207Y-289132D01*
X544909Y-289272D01*
X545611Y-289132D01*
X546207Y-288734D01*
X546605Y-288139D01*
X546744Y-287437D01*
X546605Y-286734D01*
X546207Y-286139D01*
X545611Y-285741D01*
X544909Y-285601D01*
D02*
G37*
G36*
X81880Y-285747D02*
X81177Y-285887D01*
X80582Y-286285D01*
X80184Y-286880D01*
X80044Y-287582D01*
X80184Y-288285D01*
X80582Y-288880D01*
X81177Y-289278D01*
X81880Y-289418D01*
X82582Y-289278D01*
X83177Y-288880D01*
X83575Y-288285D01*
X83715Y-287582D01*
X83575Y-286880D01*
X83177Y-286285D01*
X82582Y-285887D01*
X81880Y-285747D01*
D02*
G37*
G36*
X612598Y-289897D02*
X611896Y-290037D01*
X611301Y-290435D01*
X610903Y-291030D01*
X610763Y-291732D01*
X610903Y-292435D01*
X611301Y-293030D01*
X611896Y-293428D01*
X612598Y-293567D01*
X613301Y-293428D01*
X613896Y-293030D01*
X614294Y-292435D01*
X614434Y-291732D01*
X614294Y-291030D01*
X613896Y-290435D01*
X613301Y-290037D01*
X612598Y-289897D01*
D02*
G37*
G36*
X678441Y-290751D02*
X677738Y-290891D01*
X677143Y-291289D01*
X676745Y-291884D01*
X676605Y-292586D01*
X676745Y-293289D01*
X677143Y-293884D01*
X677738Y-294282D01*
X678441Y-294422D01*
X679143Y-294282D01*
X679738Y-293884D01*
X680136Y-293289D01*
X680276Y-292586D01*
X680136Y-291884D01*
X679738Y-291289D01*
X679143Y-290891D01*
X678441Y-290751D01*
D02*
G37*
G36*
X565354Y-291078D02*
X564652Y-291218D01*
X564057Y-291616D01*
X563659Y-292211D01*
X563519Y-292913D01*
X563659Y-293616D01*
X564057Y-294211D01*
X564652Y-294609D01*
X565354Y-294749D01*
X566057Y-294609D01*
X566652Y-294211D01*
X567050Y-293616D01*
X567190Y-292913D01*
X567050Y-292211D01*
X566652Y-291616D01*
X566057Y-291218D01*
X565354Y-291078D01*
D02*
G37*
G36*
X582874Y-292456D02*
X582172Y-292596D01*
X581576Y-292994D01*
X581178Y-293589D01*
X581039Y-294291D01*
X581178Y-294994D01*
X581576Y-295589D01*
X582172Y-295987D01*
X582874Y-296127D01*
X583576Y-295987D01*
X584172Y-295589D01*
X584570Y-294994D01*
X584709Y-294291D01*
X584570Y-293589D01*
X584172Y-292994D01*
X583576Y-292596D01*
X582874Y-292456D01*
D02*
G37*
G36*
X-23622Y-280645D02*
X-24324Y-280785D01*
X-24920Y-281183D01*
X-25318Y-281778D01*
X-25457Y-282480D01*
X-25318Y-283183D01*
X-24920Y-283778D01*
X-24324Y-284176D01*
X-24234Y-284194D01*
Y-284704D01*
X-24324Y-284722D01*
X-24920Y-285120D01*
X-25318Y-285715D01*
X-25457Y-286417D01*
X-25318Y-287120D01*
X-24920Y-287715D01*
X-24324Y-288113D01*
X-24234Y-288131D01*
Y-288641D01*
X-24324Y-288659D01*
X-24920Y-289057D01*
X-25318Y-289652D01*
X-25457Y-290354D01*
X-25318Y-291057D01*
X-24920Y-291652D01*
X-24324Y-292050D01*
X-24234Y-292068D01*
Y-292578D01*
X-24324Y-292596D01*
X-24920Y-292994D01*
X-25318Y-293589D01*
X-25457Y-294291D01*
X-25318Y-294994D01*
X-24920Y-295589D01*
X-24324Y-295987D01*
X-23622Y-296127D01*
X-22920Y-295987D01*
X-22324Y-295589D01*
X-21926Y-294994D01*
X-21787Y-294291D01*
X-21926Y-293589D01*
X-22324Y-292994D01*
X-22920Y-292596D01*
X-23010Y-292578D01*
Y-292068D01*
X-22920Y-292050D01*
X-22324Y-291652D01*
X-21926Y-291057D01*
X-21787Y-290354D01*
X-21926Y-289652D01*
X-22324Y-289057D01*
X-22920Y-288659D01*
X-23010Y-288641D01*
Y-288131D01*
X-22920Y-288113D01*
X-22324Y-287715D01*
X-21926Y-287120D01*
X-21787Y-286417D01*
X-21926Y-285715D01*
X-22324Y-285120D01*
X-22920Y-284722D01*
X-23010Y-284704D01*
Y-284194D01*
X-22920Y-284176D01*
X-22324Y-283778D01*
X-21926Y-283183D01*
X-21787Y-282480D01*
X-21926Y-281778D01*
X-22324Y-281183D01*
X-22920Y-280785D01*
X-23622Y-280645D01*
D02*
G37*
G36*
X627559Y-294621D02*
X626857Y-294761D01*
X626261Y-295159D01*
X625864Y-295754D01*
X625724Y-296457D01*
X625864Y-297159D01*
X626261Y-297754D01*
X626857Y-298152D01*
X627559Y-298292D01*
X628261Y-298152D01*
X628857Y-297754D01*
X629255Y-297159D01*
X629394Y-296457D01*
X629255Y-295754D01*
X628857Y-295159D01*
X628261Y-294761D01*
X627559Y-294621D01*
D02*
G37*
G36*
X678346Y-295409D02*
X677644Y-295549D01*
X677049Y-295946D01*
X676651Y-296542D01*
X676511Y-297244D01*
X676651Y-297946D01*
X677049Y-298542D01*
X677644Y-298940D01*
X678346Y-299079D01*
X679049Y-298940D01*
X679644Y-298542D01*
X680042Y-297946D01*
X680182Y-297244D01*
X680042Y-296542D01*
X679644Y-295946D01*
X679049Y-295549D01*
X678346Y-295409D01*
D02*
G37*
G36*
X588976Y-300921D02*
X588274Y-301060D01*
X587679Y-301458D01*
X587281Y-302054D01*
X587141Y-302756D01*
X587281Y-303458D01*
X587679Y-304054D01*
X588274Y-304451D01*
X588976Y-304591D01*
X589679Y-304451D01*
X590274Y-304054D01*
X590672Y-303458D01*
X590812Y-302756D01*
X590672Y-302054D01*
X590274Y-301458D01*
X589679Y-301060D01*
X588976Y-300921D01*
D02*
G37*
G36*
X579528Y-301314D02*
X578825Y-301454D01*
X578230Y-301852D01*
X577832Y-302447D01*
X577692Y-303150D01*
X577832Y-303852D01*
X578230Y-304447D01*
X578825Y-304845D01*
X579528Y-304985D01*
X580230Y-304845D01*
X580825Y-304447D01*
X581223Y-303852D01*
X581363Y-303150D01*
X581223Y-302447D01*
X580825Y-301852D01*
X580230Y-301454D01*
X579528Y-301314D01*
D02*
G37*
G36*
X453937Y-304907D02*
X453235Y-305046D01*
X452639Y-305444D01*
X452479D01*
X451883Y-305046D01*
X451181Y-304907D01*
X450479Y-305046D01*
X449916Y-305422D01*
X449769Y-305485D01*
X449443D01*
X449297Y-305422D01*
X448734Y-305046D01*
X448032Y-304907D01*
X447329Y-305046D01*
X447039Y-305240D01*
X446654Y-305409D01*
X446269Y-305240D01*
X445978Y-305046D01*
X445276Y-304907D01*
X444573Y-305046D01*
X444010Y-305422D01*
X443864Y-305485D01*
X443538D01*
X443391Y-305422D01*
X442828Y-305046D01*
X442126Y-304907D01*
X441424Y-305046D01*
X441133Y-305240D01*
X440748Y-305409D01*
X440363Y-305240D01*
X440072Y-305046D01*
X439370Y-304907D01*
X438668Y-305046D01*
X438105Y-305422D01*
X437958Y-305485D01*
X437632D01*
X437486Y-305422D01*
X436923Y-305046D01*
X436221Y-304907D01*
X435518Y-305046D01*
X434923Y-305444D01*
X434762D01*
X434167Y-305046D01*
X433465Y-304907D01*
X432762Y-305046D01*
X432167Y-305444D01*
X431769Y-306039D01*
X431629Y-306742D01*
X431769Y-307444D01*
X432167Y-308039D01*
X432762Y-308437D01*
X433465Y-308577D01*
X434167Y-308437D01*
X434762Y-308039D01*
X434923D01*
X435518Y-308437D01*
X436221Y-308577D01*
X436923Y-308437D01*
X437518Y-308039D01*
X437545Y-307999D01*
X438045D01*
X438072Y-308039D01*
X438668Y-308437D01*
X439370Y-308577D01*
X440072Y-308437D01*
X440363Y-308243D01*
X440748Y-308075D01*
X441133Y-308243D01*
X441424Y-308437D01*
X442126Y-308577D01*
X442828Y-308437D01*
X443391Y-308061D01*
X443538Y-307999D01*
X443864D01*
X444010Y-308061D01*
X444573Y-308437D01*
X445276Y-308577D01*
X445978Y-308437D01*
X446269Y-308243D01*
X446654Y-308075D01*
X447039Y-308243D01*
X447329Y-308437D01*
X448032Y-308577D01*
X448734Y-308437D01*
X449297Y-308061D01*
X449443Y-307999D01*
X449769D01*
X449916Y-308061D01*
X450479Y-308437D01*
X451181Y-308577D01*
X451883Y-308437D01*
X452479Y-308039D01*
X452639D01*
X453235Y-308437D01*
X453937Y-308577D01*
X454639Y-308437D01*
X455235Y-308039D01*
X455633Y-307444D01*
X455772Y-306742D01*
X455633Y-306039D01*
X455235Y-305444D01*
X454639Y-305046D01*
X453937Y-304907D01*
D02*
G37*
G36*
X470275Y-306474D02*
X469462Y-306635D01*
X468773Y-307096D01*
X468313Y-307785D01*
X468151Y-308597D01*
X468313Y-309410D01*
X468773Y-310099D01*
X469462Y-310560D01*
X470275Y-310721D01*
X471088Y-310560D01*
X471777Y-310099D01*
X472237Y-309410D01*
X472399Y-308597D01*
X472237Y-307785D01*
X471777Y-307096D01*
X471088Y-306635D01*
X470275Y-306474D01*
D02*
G37*
G36*
X391535D02*
X390722Y-306635D01*
X390033Y-307096D01*
X389573Y-307785D01*
X389411Y-308597D01*
X389573Y-309410D01*
X390033Y-310099D01*
X390722Y-310560D01*
X391535Y-310721D01*
X392348Y-310560D01*
X393037Y-310099D01*
X393497Y-309410D01*
X393659Y-308597D01*
X393497Y-307785D01*
X393037Y-307096D01*
X392348Y-306635D01*
X391535Y-306474D01*
D02*
G37*
G36*
X683858Y-308795D02*
X683156Y-308934D01*
X682560Y-309332D01*
X682163Y-309928D01*
X682023Y-310630D01*
X682163Y-311332D01*
X682560Y-311928D01*
X683156Y-312326D01*
X683858Y-312465D01*
X684561Y-312326D01*
X685156Y-311928D01*
X685554Y-311332D01*
X685694Y-310630D01*
X685554Y-309928D01*
X685156Y-309332D01*
X684561Y-308934D01*
X683858Y-308795D01*
D02*
G37*
G36*
X285128Y-301599D02*
X283756Y-301734D01*
X282436Y-302134D01*
X281220Y-302784D01*
X280154Y-303659D01*
X279279Y-304725D01*
X278629Y-305941D01*
X278229Y-307260D01*
X278094Y-308632D01*
X278229Y-310005D01*
X278629Y-311324D01*
X279279Y-312540D01*
X280154Y-313606D01*
X281220Y-314481D01*
X282436Y-315131D01*
X283756Y-315531D01*
X285128Y-315666D01*
X286500Y-315531D01*
X287820Y-315131D01*
X289036Y-314481D01*
X290102Y-313606D01*
X290976Y-312540D01*
X291626Y-311324D01*
X292027Y-310005D01*
X292162Y-308632D01*
X292027Y-307260D01*
X291626Y-305941D01*
X290976Y-304725D01*
X290102Y-303659D01*
X289036Y-302784D01*
X287820Y-302134D01*
X286500Y-301734D01*
X285128Y-301599D01*
D02*
G37*
G36*
X634252Y-312732D02*
X633550Y-312871D01*
X632954Y-313269D01*
X632556Y-313865D01*
X632417Y-314567D01*
X632556Y-315269D01*
X632954Y-315865D01*
X633550Y-316263D01*
X634252Y-316402D01*
X634954Y-316263D01*
X635550Y-315865D01*
X635948Y-315269D01*
X636087Y-314567D01*
X635948Y-313865D01*
X635550Y-313269D01*
X634954Y-312871D01*
X634252Y-312732D01*
D02*
G37*
G36*
X653150Y-312732D02*
X652447Y-312871D01*
X651852Y-313269D01*
X651454Y-313865D01*
X651314Y-314567D01*
X651454Y-315269D01*
X651852Y-315865D01*
X652447Y-316263D01*
X653150Y-316402D01*
X653852Y-316263D01*
X654447Y-315865D01*
X654845Y-315269D01*
X654985Y-314567D01*
X654845Y-313865D01*
X654447Y-313269D01*
X653852Y-312871D01*
X653150Y-312732D01*
D02*
G37*
G36*
X664966Y-314747D02*
X664263Y-314887D01*
X663668Y-315285D01*
X663270Y-315880D01*
X663130Y-316582D01*
X663270Y-317285D01*
X663668Y-317880D01*
X664263Y-318278D01*
X664966Y-318418D01*
X665668Y-318278D01*
X666263Y-317880D01*
X666661Y-317285D01*
X666801Y-316582D01*
X666661Y-315880D01*
X666263Y-315285D01*
X665668Y-314887D01*
X664966Y-314747D01*
D02*
G37*
G36*
X533015Y-305825D02*
X531662Y-305958D01*
X530360Y-306353D01*
X529160Y-306995D01*
X528109Y-307857D01*
X527246Y-308909D01*
X526605Y-310109D01*
X526210Y-311410D01*
X526076Y-312764D01*
X526210Y-314118D01*
X526605Y-315419D01*
X527246Y-316619D01*
X528109Y-317671D01*
X529160Y-318533D01*
X530360Y-319175D01*
X531662Y-319570D01*
X533015Y-319703D01*
X534369Y-319570D01*
X535671Y-319175D01*
X536870Y-318533D01*
X537922Y-317671D01*
X538785Y-316619D01*
X539426Y-315419D01*
X539821Y-314118D01*
X539954Y-312764D01*
X539821Y-311410D01*
X539426Y-310109D01*
X538785Y-308909D01*
X537922Y-307857D01*
X536870Y-306995D01*
X535671Y-306353D01*
X534369Y-305958D01*
X533015Y-305825D01*
D02*
G37*
G36*
X336515D02*
X335162Y-305958D01*
X333860Y-306353D01*
X332660Y-306995D01*
X331609Y-307857D01*
X330746Y-308909D01*
X330105Y-310109D01*
X329710Y-311410D01*
X329576Y-312764D01*
X329710Y-314118D01*
X330105Y-315419D01*
X330746Y-316619D01*
X331609Y-317671D01*
X332660Y-318533D01*
X333860Y-319175D01*
X335162Y-319570D01*
X336515Y-319703D01*
X337869Y-319570D01*
X339171Y-319175D01*
X340370Y-318533D01*
X341422Y-317671D01*
X342285Y-316619D01*
X342926Y-315419D01*
X343321Y-314118D01*
X343454Y-312764D01*
X343321Y-311410D01*
X342926Y-310109D01*
X342285Y-308909D01*
X341422Y-307857D01*
X340370Y-306995D01*
X339171Y-306353D01*
X337869Y-305958D01*
X336515Y-305825D01*
D02*
G37*
G36*
X160020Y-307502D02*
X158647Y-307637D01*
X157328Y-308037D01*
X156112Y-308687D01*
X155046Y-309562D01*
X154171Y-310628D01*
X153521Y-311844D01*
X153121Y-313163D01*
X152986Y-314535D01*
X153121Y-315908D01*
X153521Y-317227D01*
X154171Y-318443D01*
X155046Y-319509D01*
X156112Y-320384D01*
X157328Y-321034D01*
X158647Y-321434D01*
X160020Y-321569D01*
X161392Y-321434D01*
X162711Y-321034D01*
X163927Y-320384D01*
X164993Y-319509D01*
X165868Y-318443D01*
X166518Y-317227D01*
X166918Y-315908D01*
X167053Y-314535D01*
X166918Y-313163D01*
X166518Y-311844D01*
X165868Y-310628D01*
X164993Y-309562D01*
X163927Y-308687D01*
X162711Y-308037D01*
X161392Y-307637D01*
X160020Y-307502D01*
D02*
G37*
G36*
X-3528Y-311844D02*
X-13402D01*
Y-321718D01*
X-3528D01*
Y-311844D01*
D02*
G37*
G36*
X85416Y-315864D02*
X84713Y-316004D01*
X84118Y-316402D01*
X83720Y-316997D01*
X83580Y-317699D01*
X83720Y-318402D01*
X84118Y-318997D01*
X84275Y-319102D01*
X83934Y-319611D01*
X83795Y-320313D01*
X83934Y-321016D01*
X84332Y-321611D01*
X84928Y-322009D01*
X85630Y-322149D01*
X86332Y-322009D01*
X86928Y-321611D01*
X87326Y-321016D01*
X87465Y-320313D01*
X87326Y-319611D01*
X86928Y-319016D01*
X86771Y-318911D01*
X87111Y-318402D01*
X87251Y-317699D01*
X87111Y-316997D01*
X86713Y-316402D01*
X86118Y-316004D01*
X85416Y-315864D01*
D02*
G37*
G36*
X142520Y-310506D02*
X141343Y-310622D01*
X140213Y-310965D01*
X139170Y-311523D01*
X138257Y-312272D01*
X137507Y-313186D01*
X136950Y-314228D01*
X136607Y-315359D01*
X136491Y-316535D01*
X136607Y-317712D01*
X136950Y-318843D01*
X137507Y-319885D01*
X138257Y-320799D01*
X139170Y-321548D01*
X140213Y-322106D01*
X141343Y-322449D01*
X142520Y-322565D01*
X143696Y-322449D01*
X144827Y-322106D01*
X145869Y-321548D01*
X146783Y-320799D01*
X147533Y-319885D01*
X148090Y-318843D01*
X148433Y-317712D01*
X148549Y-316535D01*
X148433Y-315359D01*
X148090Y-314228D01*
X147533Y-313186D01*
X146783Y-312272D01*
X145869Y-311523D01*
X144827Y-310965D01*
X143696Y-310622D01*
X142520Y-310506D01*
D02*
G37*
G36*
X460630Y-323017D02*
X459928Y-323156D01*
X459365Y-323533D01*
X459218Y-323595D01*
X458892D01*
X458745Y-323533D01*
X458183Y-323156D01*
X457480Y-323017D01*
X456778Y-323156D01*
X456183Y-323554D01*
X456009Y-323814D01*
X455408D01*
X455235Y-323554D01*
X454639Y-323156D01*
X453937Y-323017D01*
X453235Y-323156D01*
X452639Y-323554D01*
X452479D01*
X451883Y-323156D01*
X451181Y-323017D01*
X450479Y-323156D01*
X449883Y-323554D01*
X449485Y-324150D01*
X449468Y-324240D01*
X448958D01*
X448940Y-324150D01*
X448542Y-323554D01*
X447946Y-323156D01*
X447244Y-323017D01*
X446542Y-323156D01*
X446251Y-323351D01*
X445866Y-323519D01*
X445481Y-323351D01*
X445190Y-323156D01*
X444488Y-323017D01*
X443786Y-323156D01*
X443190Y-323554D01*
X442793Y-324150D01*
X442775Y-324240D01*
X442265D01*
X442247Y-324150D01*
X441849Y-323554D01*
X441254Y-323156D01*
X440551Y-323017D01*
X439849Y-323156D01*
X439254Y-323554D01*
X439093D01*
X438498Y-323156D01*
X437795Y-323017D01*
X437093Y-323156D01*
X436498Y-323554D01*
X436100Y-324150D01*
X436082Y-324240D01*
X435572D01*
X435554Y-324150D01*
X435156Y-323554D01*
X434561Y-323156D01*
X433858Y-323017D01*
X433156Y-323156D01*
X432561Y-323554D01*
X432400D01*
X431805Y-323156D01*
X431102Y-323017D01*
X430400Y-323156D01*
X429805Y-323554D01*
X429407Y-324150D01*
X429267Y-324852D01*
X429407Y-325554D01*
X429805Y-326150D01*
X430400Y-326548D01*
X431102Y-326687D01*
X431805Y-326548D01*
X432400Y-326150D01*
X432561D01*
X433156Y-326548D01*
X433858Y-326687D01*
X434561Y-326548D01*
X435156Y-326150D01*
X435554Y-325554D01*
X435572Y-325464D01*
X436082D01*
X436100Y-325554D01*
X436498Y-326150D01*
X437093Y-326548D01*
X437795Y-326687D01*
X438498Y-326548D01*
X439093Y-326150D01*
X439254D01*
X439849Y-326548D01*
X440551Y-326687D01*
X441254Y-326548D01*
X441849Y-326150D01*
X442247Y-325554D01*
X442265Y-325464D01*
X442775D01*
X442793Y-325554D01*
X443190Y-326150D01*
X443786Y-326548D01*
X444488Y-326687D01*
X445190Y-326548D01*
X445481Y-326353D01*
X445866Y-326185D01*
X446251Y-326353D01*
X446542Y-326548D01*
X447244Y-326687D01*
X447946Y-326548D01*
X448542Y-326150D01*
X448940Y-325554D01*
X448958Y-325464D01*
X449468D01*
X449485Y-325554D01*
X449883Y-326150D01*
X450479Y-326548D01*
X451181Y-326687D01*
X451883Y-326548D01*
X452479Y-326150D01*
X452639D01*
X453235Y-326548D01*
X453937Y-326687D01*
X454639Y-326548D01*
X455235Y-326150D01*
X455408Y-325890D01*
X456009D01*
X456183Y-326150D01*
X456778Y-326548D01*
X457480Y-326687D01*
X458183Y-326548D01*
X458745Y-326171D01*
X458892Y-326109D01*
X459218D01*
X459365Y-326171D01*
X459928Y-326548D01*
X460630Y-326687D01*
X461332Y-326548D01*
X461928Y-326150D01*
X462325Y-325554D01*
X462465Y-324852D01*
X462325Y-324150D01*
X461928Y-323554D01*
X461332Y-323156D01*
X460630Y-323017D01*
D02*
G37*
G36*
X294094Y-321136D02*
X292918Y-321252D01*
X291787Y-321595D01*
X290745Y-322152D01*
X289831Y-322902D01*
X289082Y-323816D01*
X288524Y-324858D01*
X288439Y-325140D01*
X287939D01*
X287854Y-324858D01*
X287296Y-323816D01*
X286547Y-322902D01*
X285633Y-322152D01*
X284591Y-321595D01*
X283460Y-321252D01*
X282283Y-321136D01*
X281107Y-321252D01*
X279976Y-321595D01*
X278934Y-322152D01*
X278020Y-322902D01*
X277271Y-323816D01*
X276713Y-324858D01*
X276628Y-325140D01*
X276128D01*
X276043Y-324858D01*
X275485Y-323816D01*
X274736Y-322902D01*
X273822Y-322152D01*
X272780Y-321595D01*
X271649Y-321252D01*
X270472Y-321136D01*
X269296Y-321252D01*
X268165Y-321595D01*
X267123Y-322152D01*
X266209Y-322902D01*
X265459Y-323816D01*
X264902Y-324858D01*
X264734Y-325414D01*
X264211D01*
X264042Y-324858D01*
X263485Y-323816D01*
X262736Y-322902D01*
X261822Y-322152D01*
X260780Y-321595D01*
X259649Y-321252D01*
X258472Y-321136D01*
X257296Y-321252D01*
X256165Y-321595D01*
X255123Y-322152D01*
X254209Y-322902D01*
X253460Y-323816D01*
X252902Y-324858D01*
X252734Y-325414D01*
X252211D01*
X252043Y-324858D01*
X251485Y-323816D01*
X250736Y-322902D01*
X249822Y-322152D01*
X248780Y-321595D01*
X247649Y-321252D01*
X246472Y-321136D01*
X245296Y-321252D01*
X244165Y-321595D01*
X243123Y-322152D01*
X242209Y-322902D01*
X241459Y-323816D01*
X240902Y-324858D01*
X240559Y-325989D01*
X240443Y-327165D01*
X240559Y-328342D01*
X240902Y-329473D01*
X241459Y-330515D01*
X242209Y-331429D01*
X243123Y-332178D01*
X244165Y-332735D01*
X245296Y-333079D01*
X246472Y-333194D01*
X247649Y-333079D01*
X248780Y-332735D01*
X249822Y-332178D01*
X250736Y-331429D01*
X251485Y-330515D01*
X252043Y-329473D01*
X252211Y-328917D01*
X252734D01*
X252902Y-329473D01*
X253460Y-330515D01*
X254209Y-331429D01*
X255123Y-332178D01*
X256165Y-332735D01*
X257296Y-333079D01*
X258472Y-333194D01*
X259649Y-333079D01*
X260780Y-332735D01*
X261822Y-332178D01*
X262736Y-331429D01*
X263485Y-330515D01*
X264042Y-329473D01*
X264211Y-328917D01*
X264734D01*
X264902Y-329473D01*
X265459Y-330515D01*
X266209Y-331429D01*
X267123Y-332178D01*
X268165Y-332735D01*
X269296Y-333079D01*
X270472Y-333194D01*
X271649Y-333079D01*
X272780Y-332735D01*
X273822Y-332178D01*
X274736Y-331429D01*
X275485Y-330515D01*
X276043Y-329473D01*
X276128Y-329191D01*
X276628D01*
X276713Y-329473D01*
X277271Y-330515D01*
X278020Y-331429D01*
X278934Y-332178D01*
X279976Y-332735D01*
X281107Y-333079D01*
X282283Y-333194D01*
X283460Y-333079D01*
X284591Y-332735D01*
X285633Y-332178D01*
X286547Y-331429D01*
X287296Y-330515D01*
X287854Y-329473D01*
X287939Y-329191D01*
X288439D01*
X288524Y-329473D01*
X289082Y-330515D01*
X289831Y-331429D01*
X290745Y-332178D01*
X291787Y-332735D01*
X292918Y-333079D01*
X294094Y-333194D01*
X295271Y-333079D01*
X296402Y-332735D01*
X297444Y-332178D01*
X298358Y-331429D01*
X299108Y-330515D01*
X299665Y-329473D01*
X300008Y-328342D01*
X300124Y-327165D01*
X300008Y-325989D01*
X299665Y-324858D01*
X299108Y-323816D01*
X298358Y-322902D01*
X297444Y-322152D01*
X296402Y-321595D01*
X295271Y-321252D01*
X294094Y-321136D01*
D02*
G37*
G36*
X664961Y-324149D02*
X664258Y-324289D01*
X663663Y-324687D01*
X663265Y-325282D01*
X663125Y-325984D01*
X663265Y-326687D01*
X663663Y-327282D01*
X664258Y-327680D01*
X664961Y-327819D01*
X665663Y-327680D01*
X666258Y-327282D01*
X666656Y-326687D01*
X666796Y-325984D01*
X666656Y-325282D01*
X666258Y-324687D01*
X665663Y-324289D01*
X664961Y-324149D01*
D02*
G37*
G36*
X87598Y-327889D02*
X86896Y-328029D01*
X86301Y-328427D01*
X85903Y-329022D01*
X85763Y-329724D01*
X85903Y-330427D01*
X86301Y-331022D01*
X86896Y-331420D01*
X87598Y-331560D01*
X88301Y-331420D01*
X88896Y-331022D01*
X89294Y-330427D01*
X89434Y-329724D01*
X89294Y-329022D01*
X88896Y-328427D01*
X88301Y-328029D01*
X87598Y-327889D01*
D02*
G37*
G36*
X62992D02*
X62290Y-328029D01*
X61694Y-328427D01*
X61297Y-329022D01*
X61157Y-329724D01*
X61297Y-330427D01*
X61694Y-331022D01*
X62290Y-331420D01*
X62992Y-331560D01*
X63694Y-331420D01*
X64290Y-331022D01*
X64688Y-330427D01*
X64827Y-329724D01*
X64688Y-329022D01*
X64290Y-328427D01*
X63694Y-328029D01*
X62992Y-327889D01*
D02*
G37*
G36*
X604291Y-325703D02*
X603169Y-325851D01*
X602123Y-326284D01*
X601225Y-326973D01*
X600536Y-327871D01*
X600103Y-328917D01*
X599955Y-330039D01*
X600103Y-331162D01*
X600536Y-332207D01*
X601225Y-333106D01*
X602123Y-333795D01*
X603169Y-334228D01*
X604291Y-334376D01*
X605414Y-334228D01*
X606460Y-333795D01*
X607358Y-333106D01*
X608047Y-332207D01*
X608480Y-331162D01*
X608628Y-330039D01*
X608480Y-328917D01*
X608047Y-327871D01*
X607358Y-326973D01*
X606460Y-326284D01*
X605414Y-325851D01*
X604291Y-325703D01*
D02*
G37*
G36*
X574291D02*
X573169Y-325851D01*
X572123Y-326284D01*
X571225Y-326973D01*
X570536Y-327871D01*
X570103Y-328917D01*
X569955Y-330039D01*
X570103Y-331162D01*
X570536Y-332207D01*
X571225Y-333106D01*
X572123Y-333795D01*
X573169Y-334228D01*
X574291Y-334376D01*
X575414Y-334228D01*
X576460Y-333795D01*
X577358Y-333106D01*
X578047Y-332207D01*
X578480Y-331162D01*
X578628Y-330039D01*
X578480Y-328917D01*
X578047Y-327871D01*
X577358Y-326973D01*
X576460Y-326284D01*
X575414Y-325851D01*
X574291Y-325703D01*
D02*
G37*
G36*
X87598Y-333795D02*
X86896Y-333934D01*
X86301Y-334332D01*
X85903Y-334928D01*
X85763Y-335630D01*
X85903Y-336332D01*
X86301Y-336928D01*
X86896Y-337326D01*
X87598Y-337465D01*
X88301Y-337326D01*
X88896Y-336928D01*
X89294Y-336332D01*
X89434Y-335630D01*
X89294Y-334928D01*
X88896Y-334332D01*
X88301Y-333934D01*
X87598Y-333795D01*
D02*
G37*
G36*
X508997Y-333840D02*
X508295Y-333979D01*
X507699Y-334377D01*
X507302Y-334973D01*
X507162Y-335675D01*
X507302Y-336377D01*
X507699Y-336973D01*
X508295Y-337370D01*
X508997Y-337510D01*
X509699Y-337370D01*
X510295Y-336973D01*
X510693Y-336377D01*
X510832Y-335675D01*
X510693Y-334973D01*
X510295Y-334377D01*
X509699Y-333979D01*
X508997Y-333840D01*
D02*
G37*
G36*
X74803Y-337732D02*
X74101Y-337871D01*
X73505Y-338269D01*
X73108Y-338865D01*
X72968Y-339567D01*
X73108Y-340269D01*
X73505Y-340865D01*
X74101Y-341263D01*
X74803Y-341402D01*
X75506Y-341263D01*
X76101Y-340865D01*
X76431Y-340370D01*
X76879Y-340541D01*
X76907Y-340559D01*
X77045Y-341253D01*
X77442Y-341849D01*
X78038Y-342247D01*
X78740Y-342386D01*
X79443Y-342247D01*
X80038Y-341849D01*
X80436Y-341253D01*
X80575Y-340551D01*
X80436Y-339849D01*
X80038Y-339253D01*
X79443Y-338856D01*
X78740Y-338716D01*
X78038Y-338856D01*
X77442Y-339253D01*
X77112Y-339748D01*
X76664Y-339577D01*
X76637Y-339559D01*
X76499Y-338865D01*
X76101Y-338269D01*
X75506Y-337871D01*
X74803Y-337732D01*
D02*
G37*
G36*
X142520Y-341078D02*
X141817Y-341218D01*
X141222Y-341616D01*
X140824Y-342211D01*
X140684Y-342913D01*
X140824Y-343616D01*
X141222Y-344211D01*
X141817Y-344609D01*
X142520Y-344749D01*
X143222Y-344609D01*
X143817Y-344211D01*
X144215Y-343616D01*
X144355Y-342913D01*
X144215Y-342211D01*
X143817Y-341616D01*
X143222Y-341218D01*
X142520Y-341078D01*
D02*
G37*
G36*
X-23622Y-333795D02*
X-24324Y-333934D01*
X-24920Y-334332D01*
X-25318Y-334928D01*
X-25457Y-335630D01*
X-25318Y-336332D01*
X-24920Y-336928D01*
X-24324Y-337326D01*
X-24234Y-337344D01*
Y-337853D01*
X-24324Y-337871D01*
X-24920Y-338269D01*
X-25318Y-338865D01*
X-25457Y-339567D01*
X-25318Y-340269D01*
X-25032Y-340696D01*
X-24958Y-341043D01*
X-25032Y-341391D01*
X-25318Y-341817D01*
X-25457Y-342520D01*
X-25318Y-343222D01*
X-24920Y-343817D01*
X-24324Y-344215D01*
X-24234Y-344233D01*
Y-344743D01*
X-24324Y-344761D01*
X-24920Y-345159D01*
X-25318Y-345754D01*
X-25457Y-346457D01*
X-25318Y-347159D01*
X-24920Y-347754D01*
X-24324Y-348152D01*
X-23622Y-348292D01*
X-22920Y-348152D01*
X-22324Y-347754D01*
X-21926Y-347159D01*
X-21787Y-346457D01*
X-21926Y-345754D01*
X-22324Y-345159D01*
X-22920Y-344761D01*
X-23010Y-344743D01*
Y-344233D01*
X-22920Y-344215D01*
X-22324Y-343817D01*
X-21926Y-343222D01*
X-21787Y-342520D01*
X-21926Y-341817D01*
X-22212Y-341391D01*
X-22286Y-341043D01*
X-22212Y-340696D01*
X-21926Y-340269D01*
X-21787Y-339567D01*
X-21926Y-338865D01*
X-22324Y-338269D01*
X-22920Y-337871D01*
X-23010Y-337853D01*
Y-337344D01*
X-22920Y-337326D01*
X-22324Y-336928D01*
X-21926Y-336332D01*
X-21787Y-335630D01*
X-21926Y-334928D01*
X-22324Y-334332D01*
X-22920Y-333934D01*
X-23622Y-333795D01*
D02*
G37*
G36*
X141981Y-345208D02*
X141279Y-345348D01*
X140683Y-345745D01*
X140286Y-346341D01*
X140146Y-347043D01*
X140286Y-347746D01*
X140683Y-348341D01*
X141279Y-348739D01*
X141981Y-348879D01*
X142683Y-348739D01*
X143279Y-348341D01*
X143677Y-347746D01*
X143816Y-347043D01*
X143677Y-346341D01*
X143279Y-345745D01*
X142683Y-345348D01*
X141981Y-345208D01*
D02*
G37*
G36*
X509391Y-348800D02*
X508688Y-348940D01*
X508093Y-349338D01*
X507695Y-349933D01*
X507555Y-350636D01*
X507695Y-351338D01*
X508093Y-351933D01*
X508688Y-352331D01*
X509391Y-352471D01*
X510093Y-352331D01*
X510688Y-351933D01*
X511086Y-351338D01*
X511226Y-350636D01*
X511086Y-349933D01*
X510688Y-349338D01*
X510093Y-348940D01*
X509391Y-348800D01*
D02*
G37*
G36*
X486221Y-327009D02*
X484102Y-327176D01*
X482036Y-327672D01*
X480073Y-328485D01*
X478261Y-329596D01*
X476645Y-330976D01*
X475265Y-332592D01*
X474155Y-334403D01*
X473342Y-336367D01*
X472845Y-338433D01*
X472679Y-340551D01*
X472845Y-342670D01*
X473342Y-344736D01*
X474155Y-346699D01*
X475265Y-348511D01*
X476645Y-350127D01*
X478261Y-351507D01*
X480073Y-352617D01*
X482036Y-353430D01*
X484102Y-353926D01*
X486221Y-354093D01*
X488339Y-353926D01*
X490405Y-353430D01*
X492368Y-352617D01*
X494180Y-351507D01*
X495796Y-350127D01*
X497176Y-348511D01*
X498286Y-346699D01*
X499099Y-344736D01*
X499595Y-342670D01*
X499762Y-340551D01*
X499595Y-338433D01*
X499099Y-336367D01*
X498286Y-334403D01*
X497176Y-332592D01*
X495796Y-330976D01*
X494180Y-329596D01*
X492368Y-328485D01*
X490405Y-327672D01*
X488339Y-327176D01*
X486221Y-327009D01*
D02*
G37*
G36*
X685039Y-327010D02*
X682921Y-327176D01*
X680855Y-327672D01*
X678892Y-328485D01*
X677080Y-329596D01*
X675464Y-330976D01*
X674084Y-332592D01*
X672974Y-334403D01*
X672160Y-336367D01*
X671664Y-338433D01*
X671498Y-340551D01*
X671664Y-342670D01*
X672160Y-344736D01*
X672974Y-346699D01*
X674084Y-348511D01*
X675464Y-350127D01*
X677080Y-351507D01*
X678892Y-352617D01*
X680855Y-353430D01*
X682921Y-353926D01*
X685039Y-354093D01*
X687158Y-353926D01*
X689224Y-353430D01*
X691187Y-352617D01*
X692999Y-351507D01*
X694615Y-350127D01*
X695995Y-348511D01*
X697105Y-346699D01*
X697918Y-344736D01*
X698414Y-342670D01*
X698581Y-340551D01*
X698414Y-338433D01*
X697918Y-336367D01*
X697105Y-334403D01*
X695995Y-332592D01*
X694615Y-330976D01*
X692999Y-329596D01*
X691187Y-328485D01*
X689224Y-327672D01*
X687158Y-327176D01*
X685039Y-327010D01*
D02*
G37*
G36*
X157480Y-356826D02*
X156778Y-356966D01*
X156496Y-357154D01*
X156214Y-356966D01*
X155512Y-356826D01*
X154809Y-356966D01*
X154528Y-357154D01*
X154246Y-356966D01*
X153543Y-356826D01*
X152841Y-356966D01*
X152246Y-357364D01*
X151848Y-357959D01*
X151708Y-358661D01*
X151848Y-359364D01*
X152246Y-359959D01*
X152286Y-359986D01*
Y-360486D01*
X152246Y-360513D01*
X151848Y-361109D01*
X151708Y-361811D01*
X151848Y-362513D01*
X152246Y-363109D01*
X152841Y-363507D01*
X153543Y-363646D01*
X154246Y-363507D01*
X154528Y-363318D01*
X154809Y-363507D01*
X155512Y-363646D01*
X156214Y-363507D01*
X156496Y-363318D01*
X156778Y-363507D01*
X157480Y-363646D01*
X158183Y-363507D01*
X158778Y-363109D01*
X159176Y-362513D01*
X159316Y-361811D01*
X159176Y-361109D01*
X158778Y-360513D01*
X158738Y-360486D01*
Y-359986D01*
X158778Y-359959D01*
X159176Y-359364D01*
X159316Y-358661D01*
X159176Y-357959D01*
X158778Y-357364D01*
X158183Y-356966D01*
X157480Y-356826D01*
D02*
G37*
G36*
X198392Y-365007D02*
X197690Y-365146D01*
X197094Y-365544D01*
X196697Y-366140D01*
X196557Y-366842D01*
X196697Y-367544D01*
X197094Y-368140D01*
X197343Y-368306D01*
X197148Y-368777D01*
X196701Y-368688D01*
X195999Y-368828D01*
X195403Y-369225D01*
X195005Y-369821D01*
X194866Y-370523D01*
X195005Y-371225D01*
X195403Y-371821D01*
X195999Y-372219D01*
X196701Y-372358D01*
X197403Y-372219D01*
X197998Y-371821D01*
X198396Y-371225D01*
X198536Y-370523D01*
X198396Y-369821D01*
X197998Y-369225D01*
X197750Y-369059D01*
X197945Y-368588D01*
X198392Y-368677D01*
X199094Y-368537D01*
X199690Y-368140D01*
X200088Y-367544D01*
X200227Y-366842D01*
X200088Y-366140D01*
X199690Y-365544D01*
X199094Y-365146D01*
X198392Y-365007D01*
D02*
G37*
G36*
X241929Y-372820D02*
X241227Y-372960D01*
X240631Y-373357D01*
X240234Y-373953D01*
X240215Y-374043D01*
X239706D01*
X239688Y-373953D01*
X239290Y-373357D01*
X238695Y-372960D01*
X237992Y-372820D01*
X237290Y-372960D01*
X236694Y-373357D01*
X236297Y-373953D01*
X236157Y-374655D01*
X236297Y-375357D01*
X236694Y-375953D01*
X237290Y-376351D01*
X237992Y-376490D01*
X238695Y-376351D01*
X239290Y-375953D01*
X239688Y-375357D01*
X239706Y-375267D01*
X240215D01*
X240234Y-375357D01*
X240631Y-375953D01*
X241227Y-376351D01*
X241929Y-376490D01*
X242632Y-376351D01*
X243227Y-375953D01*
X243625Y-375357D01*
X243764Y-374655D01*
X243625Y-373953D01*
X243227Y-373357D01*
X242632Y-372960D01*
X241929Y-372820D01*
D02*
G37*
G36*
X210433D02*
X209731Y-372960D01*
X209135Y-373357D01*
X208737Y-373953D01*
X208719Y-374043D01*
X208210D01*
X208192Y-373953D01*
X207794Y-373357D01*
X207198Y-372960D01*
X206496Y-372820D01*
X205794Y-372960D01*
X205198Y-373357D01*
X204801Y-373953D01*
X204661Y-374655D01*
X204801Y-375357D01*
X205198Y-375953D01*
X205794Y-376351D01*
X206496Y-376490D01*
X207198Y-376351D01*
X207794Y-375953D01*
X208192Y-375357D01*
X208210Y-375267D01*
X208719D01*
X208737Y-375357D01*
X209135Y-375953D01*
X209731Y-376351D01*
X210433Y-376490D01*
X211135Y-376351D01*
X211731Y-375953D01*
X212129Y-375357D01*
X212268Y-374655D01*
X212129Y-373953D01*
X211731Y-373357D01*
X211135Y-372960D01*
X210433Y-372820D01*
D02*
G37*
G36*
X218445Y-372272D02*
X217743Y-372412D01*
X217147Y-372810D01*
X216749Y-373405D01*
X216610Y-374108D01*
X216749Y-374810D01*
X217147Y-375405D01*
X217743Y-375803D01*
X218445Y-375943D01*
X219147Y-375803D01*
X219743Y-375405D01*
X220141Y-374810D01*
X220280Y-374108D01*
X220141Y-373405D01*
X219743Y-372810D01*
X219147Y-372412D01*
X218445Y-372272D01*
D02*
G37*
G36*
X269502Y-372456D02*
X268800Y-372595D01*
X268205Y-372993D01*
X267807Y-373589D01*
X267667Y-374291D01*
X267807Y-374993D01*
X268205Y-375589D01*
X268800Y-375987D01*
X269502Y-376126D01*
X270205Y-375987D01*
X270800Y-375589D01*
X271159Y-375051D01*
X271393Y-375038D01*
X271679Y-375104D01*
X271730Y-375357D01*
X272128Y-375953D01*
X272723Y-376351D01*
X273425Y-376490D01*
X274128Y-376351D01*
X274723Y-375953D01*
X275121Y-375357D01*
X275260Y-374655D01*
X275121Y-373953D01*
X274723Y-373357D01*
X274128Y-372960D01*
X273425Y-372820D01*
X272723Y-372960D01*
X272128Y-373357D01*
X271769Y-373895D01*
X271535Y-373908D01*
X271248Y-373842D01*
X271198Y-373589D01*
X270800Y-372993D01*
X270205Y-372595D01*
X269502Y-372456D01*
D02*
G37*
G36*
X253655Y-372586D02*
X252953Y-372726D01*
X252357Y-373123D01*
X251959Y-373719D01*
X251820Y-374421D01*
X251959Y-375123D01*
X252357Y-375719D01*
X252953Y-376117D01*
X253655Y-376256D01*
X254357Y-376117D01*
X254953Y-375719D01*
X255436D01*
X255592Y-375953D01*
X256187Y-376351D01*
X256890Y-376490D01*
X257592Y-376351D01*
X258188Y-375953D01*
X258585Y-375357D01*
X258725Y-374655D01*
X258585Y-373953D01*
X258188Y-373357D01*
X257592Y-372960D01*
X256890Y-372820D01*
X256187Y-372960D01*
X255592Y-373357D01*
X255109D01*
X254953Y-373123D01*
X254357Y-372726D01*
X253655Y-372586D01*
D02*
G37*
G36*
X222638Y-372820D02*
X221936Y-372960D01*
X221340Y-373357D01*
X220942Y-373953D01*
X220802Y-374655D01*
X220942Y-375357D01*
X221340Y-375953D01*
X221936Y-376351D01*
X222638Y-376490D01*
X223340Y-376351D01*
X223936Y-375953D01*
X224333Y-375357D01*
X224473Y-374655D01*
X224333Y-373953D01*
X223936Y-373357D01*
X223340Y-372960D01*
X222638Y-372820D01*
D02*
G37*
G36*
X190354Y-375576D02*
X189652Y-375715D01*
X189057Y-376113D01*
X188659Y-376709D01*
X188519Y-377411D01*
X188659Y-378113D01*
X189057Y-378709D01*
X189652Y-379107D01*
X190354Y-379246D01*
X191057Y-379107D01*
X191652Y-378709D01*
X192050Y-378113D01*
X192190Y-377411D01*
X192050Y-376709D01*
X191652Y-376113D01*
X191057Y-375715D01*
X190354Y-375576D01*
D02*
G37*
G36*
X178543D02*
X177841Y-375715D01*
X177246Y-376113D01*
X176848Y-376709D01*
X176708Y-377411D01*
X176848Y-378113D01*
X177246Y-378709D01*
X177841Y-379107D01*
X178543Y-379246D01*
X179246Y-379107D01*
X179841Y-378709D01*
X180239Y-378113D01*
X180379Y-377411D01*
X180239Y-376709D01*
X179841Y-376113D01*
X179246Y-375715D01*
X178543Y-375576D01*
D02*
G37*
G36*
X158661Y-384631D02*
X157959Y-384771D01*
X157677Y-384959D01*
X157395Y-384771D01*
X156693Y-384631D01*
X155991Y-384771D01*
X155709Y-384959D01*
X155427Y-384771D01*
X154724Y-384631D01*
X154022Y-384771D01*
X153427Y-385168D01*
X153029Y-385764D01*
X152889Y-386466D01*
X153029Y-387169D01*
X153427Y-387764D01*
X153467Y-387791D01*
Y-388291D01*
X153427Y-388318D01*
X153029Y-388913D01*
X152889Y-389616D01*
X153029Y-390318D01*
X153427Y-390914D01*
X154022Y-391311D01*
X154724Y-391451D01*
X155427Y-391311D01*
X155709Y-391123D01*
X155991Y-391311D01*
X156693Y-391451D01*
X157395Y-391311D01*
X157677Y-391123D01*
X157959Y-391311D01*
X158661Y-391451D01*
X159364Y-391311D01*
X159959Y-390914D01*
X160357Y-390318D01*
X160497Y-389616D01*
X160357Y-388913D01*
X159959Y-388318D01*
X159919Y-388291D01*
Y-387791D01*
X159959Y-387764D01*
X160357Y-387169D01*
X160497Y-386466D01*
X160357Y-385764D01*
X159959Y-385168D01*
X159364Y-384771D01*
X158661Y-384631D01*
D02*
G37*
G36*
X186614D02*
X185912Y-384771D01*
X185317Y-385168D01*
X184919Y-385764D01*
X184901Y-385855D01*
X184391D01*
X184373Y-385764D01*
X183975Y-385168D01*
X183379Y-384771D01*
X182677Y-384631D01*
X181975Y-384771D01*
X181379Y-385168D01*
X181206Y-385428D01*
X180605D01*
X180432Y-385168D01*
X179836Y-384771D01*
X179134Y-384631D01*
X178431Y-384771D01*
X177836Y-385168D01*
X177438Y-385764D01*
X177299Y-386466D01*
X177438Y-387169D01*
X177836Y-387764D01*
X177877Y-387791D01*
Y-388291D01*
X177836Y-388318D01*
X177438Y-388913D01*
X177299Y-389616D01*
X177438Y-390318D01*
X177836Y-390914D01*
X178431Y-391311D01*
X179134Y-391451D01*
X179836Y-391311D01*
X180432Y-390914D01*
X180605Y-390654D01*
X181206D01*
X181379Y-390914D01*
X181975Y-391311D01*
X182677Y-391451D01*
X183379Y-391311D01*
X183975Y-390914D01*
X184373Y-390318D01*
X184391Y-390227D01*
X184901D01*
X184919Y-390318D01*
X185317Y-390914D01*
X185912Y-391311D01*
X186614Y-391451D01*
X187317Y-391311D01*
X187912Y-390914D01*
X188310Y-390318D01*
X188449Y-389616D01*
X188310Y-388913D01*
X187912Y-388318D01*
X187871Y-388291D01*
Y-387791D01*
X187912Y-387764D01*
X188310Y-387169D01*
X188449Y-386466D01*
X188310Y-385764D01*
X187912Y-385168D01*
X187317Y-384771D01*
X186614Y-384631D01*
D02*
G37*
G36*
X232480Y-385418D02*
X231778Y-385558D01*
X231215Y-385934D01*
X231069Y-385996D01*
X230743D01*
X230596Y-385934D01*
X230033Y-385558D01*
X229331Y-385418D01*
X228628Y-385558D01*
X228033Y-385956D01*
X227635Y-386551D01*
X227496Y-387253D01*
X227635Y-387956D01*
X228033Y-388551D01*
X228628Y-388949D01*
X229331Y-389089D01*
X230033Y-388949D01*
X230596Y-388573D01*
X230743Y-388511D01*
X231069D01*
X231215Y-388573D01*
X231778Y-388949D01*
X232480Y-389089D01*
X233183Y-388949D01*
X233778Y-388551D01*
X234176Y-387956D01*
X234316Y-387253D01*
X234176Y-386551D01*
X233778Y-385956D01*
X233183Y-385558D01*
X232480Y-385418D01*
D02*
G37*
G36*
X215945D02*
X215243Y-385558D01*
X214680Y-385934D01*
X214533Y-385996D01*
X214207D01*
X214060Y-385934D01*
X213498Y-385558D01*
X212795Y-385418D01*
X212093Y-385558D01*
X211498Y-385956D01*
X211100Y-386551D01*
X210960Y-387253D01*
X211100Y-387956D01*
X211498Y-388551D01*
X212093Y-388949D01*
X212795Y-389089D01*
X213498Y-388949D01*
X214060Y-388573D01*
X214207Y-388511D01*
X214533D01*
X214680Y-388573D01*
X215243Y-388949D01*
X215945Y-389089D01*
X216647Y-388949D01*
X217243Y-388551D01*
X217640Y-387956D01*
X217780Y-387253D01*
X217640Y-386551D01*
X217243Y-385956D01*
X216647Y-385558D01*
X215945Y-385418D01*
D02*
G37*
G36*
X265158D02*
X264455Y-385558D01*
X263890Y-385935D01*
X263746Y-385999D01*
X263331D01*
X263304Y-385958D01*
X262708Y-385560D01*
X262006Y-385420D01*
X261304Y-385560D01*
X260708Y-385958D01*
X260311Y-386553D01*
X260171Y-387255D01*
X260311Y-387958D01*
X260708Y-388553D01*
X261304Y-388951D01*
X262006Y-389090D01*
X262708Y-388951D01*
X263273Y-388574D01*
X263417Y-388510D01*
X263832D01*
X263860Y-388551D01*
X264455Y-388949D01*
X265158Y-389089D01*
X265860Y-388949D01*
X266455Y-388551D01*
X266853Y-387956D01*
X266993Y-387253D01*
X266853Y-386551D01*
X266455Y-385956D01*
X265860Y-385558D01*
X265158Y-385418D01*
D02*
G37*
G36*
X246339Y-385140D02*
X245636Y-385279D01*
X245041Y-385677D01*
X244643Y-386273D01*
X244503Y-386975D01*
X244643Y-387677D01*
X245041Y-388273D01*
X245636Y-388671D01*
X246339Y-388810D01*
X247041Y-388671D01*
X247476Y-388380D01*
X248059Y-388472D01*
X248112Y-388551D01*
X248707Y-388949D01*
X249410Y-389089D01*
X250112Y-388949D01*
X250707Y-388551D01*
X251105Y-387956D01*
X251245Y-387253D01*
X251105Y-386551D01*
X250707Y-385956D01*
X250112Y-385558D01*
X249410Y-385418D01*
X248707Y-385558D01*
X248327Y-385812D01*
X247689Y-385756D01*
X247636Y-385677D01*
X247041Y-385279D01*
X246339Y-385140D01*
D02*
G37*
G36*
X0Y-364854D02*
X-2118Y-365020D01*
X-4185Y-365516D01*
X-6148Y-366330D01*
X-7960Y-367440D01*
X-9575Y-368820D01*
X-10955Y-370436D01*
X-12066Y-372248D01*
X-12879Y-374211D01*
X-13375Y-376277D01*
X-13542Y-378395D01*
X-13375Y-380514D01*
X-12879Y-382580D01*
X-12066Y-384543D01*
X-10955Y-386355D01*
X-9575Y-387971D01*
X-7960Y-389351D01*
X-6148Y-390461D01*
X-4185Y-391274D01*
X-2118Y-391770D01*
X0Y-391937D01*
X2118Y-391770D01*
X4185Y-391274D01*
X6148Y-390461D01*
X7960Y-389351D01*
X9576Y-387971D01*
X10955Y-386355D01*
X12066Y-384543D01*
X12879Y-382580D01*
X13375Y-380514D01*
X13542Y-378395D01*
X13375Y-376277D01*
X12879Y-374211D01*
X12066Y-372248D01*
X10955Y-370436D01*
X9576Y-368820D01*
X7960Y-367440D01*
X6148Y-366330D01*
X4185Y-365516D01*
X2118Y-365020D01*
X0Y-364854D01*
D02*
G37*
%LPD*%
D212*
X695866Y-105610D02*
D03*
Y-72342D02*
D03*
X688976D02*
D03*
Y-105610D02*
D03*
D213*
X682283Y-74803D02*
D03*
Y-103150D02*
D03*
D215*
X643701Y-127445D02*
D03*
D216*
Y-143945D02*
D03*
D240*
X171496Y-120079D02*
D03*
D241*
X142520Y-236614D02*
D03*
X302362Y-316535D02*
D03*
D03*
X142520Y-236614D02*
D03*
D245*
X-18464Y-326781D02*
D03*
X1535D02*
D03*
Y-306781D02*
D03*
X-18464D02*
D03*
X-18465Y-273630D02*
D03*
X1535D02*
D03*
Y-253630D02*
D03*
X-18465D02*
D03*
Y-220480D02*
D03*
X1535D02*
D03*
Y-200480D02*
D03*
X-18465D02*
D03*
X-18464Y-167332D02*
D03*
X1535D02*
D03*
Y-147332D02*
D03*
X-18464D02*
D03*
D248*
X549055Y13937D02*
D03*
Y3937D02*
D03*
D250*
X84079Y-105653D02*
D03*
X62499Y-117255D02*
D03*
X585433Y-114961D02*
D03*
X584252Y-117717D02*
D03*
X555512Y-218504D02*
D03*
X430492Y-136473D02*
D03*
X414567Y-137402D02*
D03*
X692037Y-315878D02*
D03*
X692126Y-322441D02*
D03*
X248425Y-129134D02*
D03*
X241077Y-118805D02*
D03*
X255512Y-121260D02*
D03*
X253713Y-109190D02*
D03*
X267717Y-123622D02*
D03*
X267323Y-132677D02*
D03*
X272047Y-131496D02*
D03*
X244664Y-106952D02*
D03*
X609055Y-92520D02*
D03*
X629134Y-102756D02*
D03*
X631814Y-83784D02*
D03*
X629101Y-90137D02*
D03*
X616535Y-84646D02*
D03*
X616929Y-100000D02*
D03*
X569291Y-91339D02*
D03*
X584763Y-100116D02*
D03*
X588976Y-86221D02*
D03*
X600394Y-87795D02*
D03*
X666929Y-98032D02*
D03*
X662539Y-107066D02*
D03*
X696762Y-63288D02*
D03*
X685716Y-22157D02*
D03*
X679517Y-26553D02*
D03*
X693915Y-33393D02*
D03*
X686728Y-33442D02*
D03*
X675926Y-72691D02*
D03*
X660719Y-75726D02*
D03*
X694095Y-62205D02*
D03*
X693977Y-53201D02*
D03*
X676378Y-83858D02*
D03*
X569092Y-108048D02*
D03*
X546386Y-109024D02*
D03*
X548093Y-185219D02*
D03*
X548425Y-181890D02*
D03*
X548819Y-178740D02*
D03*
X547244Y-157087D02*
D03*
Y-144488D02*
D03*
X524409Y-135827D02*
D03*
X531801Y-127495D02*
D03*
X639764Y-283858D02*
D03*
X554724Y-294882D02*
D03*
X680709Y-212205D02*
D03*
X673622Y-213779D02*
D03*
X669685D02*
D03*
X666142Y-212992D02*
D03*
X599564Y-178940D02*
D03*
X594882Y-179134D02*
D03*
X589764D02*
D03*
X584646Y-178740D02*
D03*
X635827Y-187795D02*
D03*
X635433Y-184252D02*
D03*
X652756Y-164961D02*
D03*
X657480Y-164567D02*
D03*
X662992Y-164961D02*
D03*
X668504D02*
D03*
X681496Y-179528D02*
D03*
X677165Y-172441D02*
D03*
X673228D02*
D03*
X650000Y-231102D02*
D03*
X646434Y-231245D02*
D03*
X570079Y-200000D02*
D03*
X600000Y-248425D02*
D03*
X616535Y-255512D02*
D03*
X612205Y-251575D02*
D03*
X624803Y-255906D02*
D03*
Y-251575D02*
D03*
X624409Y-248031D02*
D03*
X611417Y-247638D02*
D03*
X605118Y-244488D02*
D03*
X673228Y-251181D02*
D03*
X672835Y-257087D02*
D03*
X673622Y-261417D02*
D03*
X676378Y-266142D02*
D03*
X676772Y-270866D02*
D03*
X671260Y-274803D02*
D03*
Y-278740D02*
D03*
X671654Y-283071D02*
D03*
X683716Y-298538D02*
D03*
X637795Y-297638D02*
D03*
X559842Y-257087D02*
D03*
X579134Y-195276D02*
D03*
X574803D02*
D03*
X577953Y-198819D02*
D03*
X590158Y-226378D02*
D03*
X586221Y-226772D02*
D03*
X579921Y-227559D02*
D03*
X576772Y-228740D02*
D03*
X586537Y-234843D02*
D03*
X546850Y-213779D02*
D03*
X548819Y-196063D02*
D03*
X554724Y-207874D02*
D03*
X571162Y-284136D02*
D03*
X577953Y-284646D02*
D03*
X574803Y-284252D02*
D03*
X568110D02*
D03*
X567717Y-259055D02*
D03*
X566535Y-255906D02*
D03*
X570079D02*
D03*
X548425Y-253543D02*
D03*
X545669Y-253937D02*
D03*
X545128Y-280872D02*
D03*
X545276Y-294094D02*
D03*
X544488Y-265748D02*
D03*
X595276Y-291732D02*
D03*
X488583Y-132283D02*
D03*
X506299Y-129921D02*
D03*
X506207Y-127333D02*
D03*
X501669Y-116601D02*
D03*
X500313Y-105734D02*
D03*
X476772Y-123622D02*
D03*
X470472Y-123622D02*
D03*
X444507Y-309009D02*
D03*
X448819Y-309055D02*
D03*
X457480Y-306693D02*
D03*
X451575Y-309055D02*
D03*
X437048Y-308863D02*
D03*
X431102Y-308268D02*
D03*
X461811Y-327165D02*
D03*
X456693D02*
D03*
X454724D02*
D03*
X450394D02*
D03*
X448032D02*
D03*
X443701D02*
D03*
X441732D02*
D03*
X436614D02*
D03*
X429528Y-326772D02*
D03*
X434646Y-327559D02*
D03*
X623622Y-70866D02*
D03*
X43701Y-29921D02*
D03*
X55905Y-31496D02*
D03*
X111024Y-33071D02*
D03*
X125591Y-32283D02*
D03*
X101181Y-18504D02*
D03*
X670079Y-9449D02*
D03*
X673228Y-29528D02*
D03*
X671654Y-62598D02*
D03*
Y-41339D02*
D03*
X596063Y-53937D02*
D03*
X602756Y-39764D02*
D03*
X315097Y-235081D02*
D03*
X287941Y-241819D02*
D03*
X288189Y-235827D02*
D03*
X615748Y-305512D02*
D03*
X562598Y-306693D02*
D03*
X531496Y-262647D02*
D03*
X461811Y-310679D02*
D03*
X450000Y-293750D02*
D03*
X422441Y-293789D02*
D03*
X531496Y-213435D02*
D03*
X338525Y-243567D02*
D03*
X525591Y-233088D02*
D03*
X439697Y-162549D02*
D03*
X343144Y-225173D02*
D03*
X420669Y-157923D02*
D03*
X531496Y-223277D02*
D03*
X338583Y-235236D02*
D03*
X525591Y-242962D02*
D03*
X430150Y-162253D02*
D03*
X343444Y-215373D02*
D03*
X432283Y-293750D02*
D03*
X410528Y-157923D02*
D03*
X342944Y-264473D02*
D03*
X444095Y-293750D02*
D03*
X422835Y-311072D02*
D03*
X531496Y-233088D02*
D03*
X430150Y-157923D02*
D03*
X338444Y-225173D02*
D03*
X402756Y-311072D02*
D03*
X525591Y-253969D02*
D03*
X420079Y-162549D02*
D03*
X343403Y-205651D02*
D03*
X525591Y-203592D02*
D03*
X400295Y-157824D02*
D03*
X343144Y-254773D02*
D03*
X431928Y-311189D02*
D03*
X531496Y-242962D02*
D03*
X338844Y-215273D02*
D03*
X402362Y-293750D02*
D03*
X525591Y-262647D02*
D03*
X410913Y-162758D02*
D03*
X338444Y-264473D02*
D03*
X456299Y-293750D02*
D03*
X437795Y-293750D02*
D03*
X525591Y-213435D02*
D03*
X459319Y-162510D02*
D03*
Y-157922D02*
D03*
X342744Y-243747D02*
D03*
X412598Y-311072D02*
D03*
X531496Y-253969D02*
D03*
X449803Y-157923D02*
D03*
X338744Y-205473D02*
D03*
X531496Y-203592D02*
D03*
X401279Y-162509D02*
D03*
X439961Y-157923D02*
D03*
X338444Y-254773D02*
D03*
X461417Y-293750D02*
D03*
X525591Y-223277D02*
D03*
X449508Y-162549D02*
D03*
X343504Y-235236D02*
D03*
X412205Y-293750D02*
D03*
X639750Y-314581D02*
D03*
X658647Y-314581D02*
D03*
X509405Y-345138D02*
D03*
X509011Y-330177D02*
D03*
X56441Y-143600D02*
D03*
Y-151600D02*
D03*
Y-191600D02*
D03*
Y-199600D02*
D03*
Y-215600D02*
D03*
Y-223600D02*
D03*
Y-231600D02*
D03*
Y-247600D02*
D03*
Y-255600D02*
D03*
Y-271600D02*
D03*
Y-279600D02*
D03*
Y-287600D02*
D03*
Y-303600D02*
D03*
Y-311600D02*
D03*
Y-327600D02*
D03*
Y-335600D02*
D03*
Y-343600D02*
D03*
Y-351600D02*
D03*
X54441Y-139600D02*
D03*
X52441Y-143600D02*
D03*
X54441Y-147600D02*
D03*
X52441Y-151600D02*
D03*
Y-191600D02*
D03*
X54441Y-195600D02*
D03*
X52441Y-199600D02*
D03*
X54441Y-203600D02*
D03*
X52441Y-215600D02*
D03*
X54441Y-219600D02*
D03*
X52441Y-223600D02*
D03*
X54441Y-227600D02*
D03*
X52441Y-231600D02*
D03*
X54441Y-235600D02*
D03*
Y-243600D02*
D03*
X52441Y-247600D02*
D03*
X54441Y-251600D02*
D03*
X52441Y-255600D02*
D03*
X54441Y-267600D02*
D03*
X52441Y-271600D02*
D03*
X54441Y-275600D02*
D03*
X52441Y-279600D02*
D03*
Y-287600D02*
D03*
X54441Y-291600D02*
D03*
Y-299600D02*
D03*
X52441Y-303600D02*
D03*
X54441Y-307600D02*
D03*
X52441Y-311600D02*
D03*
X54441Y-323600D02*
D03*
X52441Y-327600D02*
D03*
X54441Y-331600D02*
D03*
X52441Y-335600D02*
D03*
X54441Y-339600D02*
D03*
X52441Y-343600D02*
D03*
Y-351600D02*
D03*
X50441Y-139600D02*
D03*
X48441Y-143600D02*
D03*
X50441Y-195600D02*
D03*
X48441Y-199600D02*
D03*
Y-223600D02*
D03*
X50441Y-227600D02*
D03*
X48441Y-231600D02*
D03*
X50441Y-235600D02*
D03*
Y-243600D02*
D03*
X48441Y-247600D02*
D03*
X50441Y-251600D02*
D03*
Y-275600D02*
D03*
X48441Y-279600D02*
D03*
Y-287600D02*
D03*
X50441Y-291600D02*
D03*
Y-299600D02*
D03*
X48441Y-303600D02*
D03*
X50441Y-331600D02*
D03*
X48441Y-335600D02*
D03*
X50441Y-339600D02*
D03*
X48441Y-343600D02*
D03*
Y-351600D02*
D03*
X46441Y-139600D02*
D03*
X44441Y-143600D02*
D03*
X46441Y-227600D02*
D03*
X44441Y-231600D02*
D03*
X46441Y-235600D02*
D03*
Y-243600D02*
D03*
X44441Y-247600D02*
D03*
Y-279600D02*
D03*
Y-287600D02*
D03*
X46441Y-291600D02*
D03*
Y-299600D02*
D03*
Y-331600D02*
D03*
X44441Y-335600D02*
D03*
X46441Y-339600D02*
D03*
X44441Y-343600D02*
D03*
Y-351600D02*
D03*
X42441Y-139600D02*
D03*
X40441Y-143600D02*
D03*
Y-223600D02*
D03*
X42441Y-227600D02*
D03*
X40441Y-231600D02*
D03*
X42441Y-235600D02*
D03*
Y-243600D02*
D03*
X40441Y-247600D02*
D03*
X42441Y-299600D02*
D03*
Y-331600D02*
D03*
X40441Y-335600D02*
D03*
X42441Y-339600D02*
D03*
X40441Y-343600D02*
D03*
Y-351600D02*
D03*
X38441Y-139600D02*
D03*
X36441Y-143600D02*
D03*
Y-151600D02*
D03*
Y-215600D02*
D03*
Y-223600D02*
D03*
X38441Y-227600D02*
D03*
X36441Y-231600D02*
D03*
X38441Y-235600D02*
D03*
Y-243600D02*
D03*
X36441Y-247600D02*
D03*
X38441Y-251600D02*
D03*
X36441Y-255600D02*
D03*
Y-327600D02*
D03*
X38441Y-331600D02*
D03*
X36441Y-335600D02*
D03*
X38441Y-339600D02*
D03*
X36441Y-343600D02*
D03*
Y-351600D02*
D03*
X34441Y-139600D02*
D03*
X32441Y-143600D02*
D03*
X34441Y-147600D02*
D03*
X32441Y-151600D02*
D03*
X34441Y-163600D02*
D03*
Y-219600D02*
D03*
Y-227600D02*
D03*
Y-235600D02*
D03*
Y-243600D02*
D03*
Y-251600D02*
D03*
Y-267600D02*
D03*
Y-275600D02*
D03*
Y-299600D02*
D03*
Y-307600D02*
D03*
Y-323600D02*
D03*
X32441Y-327600D02*
D03*
X34441Y-331600D02*
D03*
X32441Y-335600D02*
D03*
X34441Y-339600D02*
D03*
X32441Y-343600D02*
D03*
Y-351600D02*
D03*
X30441Y-139600D02*
D03*
X28441Y-143600D02*
D03*
X30441Y-147600D02*
D03*
X28441Y-151600D02*
D03*
X30441Y-163600D02*
D03*
X28441Y-167600D02*
D03*
Y-327600D02*
D03*
X30441Y-331600D02*
D03*
X28441Y-335600D02*
D03*
X30441Y-339600D02*
D03*
X28441Y-343600D02*
D03*
Y-351600D02*
D03*
X26441Y-139600D02*
D03*
X24441Y-143600D02*
D03*
X26441Y-147600D02*
D03*
X24441Y-151600D02*
D03*
X26441Y-163600D02*
D03*
X24441Y-167600D02*
D03*
Y-191600D02*
D03*
X26441Y-195600D02*
D03*
X24441Y-287600D02*
D03*
X26441Y-299600D02*
D03*
X24441Y-303600D02*
D03*
X26441Y-307600D02*
D03*
X24441Y-311600D02*
D03*
X26441Y-331600D02*
D03*
X24441Y-335600D02*
D03*
X26441Y-339600D02*
D03*
X24441Y-343600D02*
D03*
Y-351600D02*
D03*
X22441Y-139600D02*
D03*
X20441Y-143600D02*
D03*
X22441Y-147600D02*
D03*
X20441Y-151600D02*
D03*
X22441Y-163600D02*
D03*
X20441Y-167600D02*
D03*
X22441Y-171600D02*
D03*
X20441Y-191600D02*
D03*
X22441Y-195600D02*
D03*
X20441Y-199600D02*
D03*
Y-231600D02*
D03*
X22441Y-235600D02*
D03*
Y-243600D02*
D03*
X20441Y-247600D02*
D03*
X22441Y-251600D02*
D03*
X20441Y-255600D02*
D03*
X22441Y-259600D02*
D03*
Y-267600D02*
D03*
X20441Y-271600D02*
D03*
X22441Y-283600D02*
D03*
X20441Y-287600D02*
D03*
X22441Y-291600D02*
D03*
Y-299600D02*
D03*
X20441Y-303600D02*
D03*
X22441Y-307600D02*
D03*
X20441Y-311600D02*
D03*
X22441Y-323600D02*
D03*
X20441Y-335600D02*
D03*
X22441Y-339600D02*
D03*
X20441Y-343600D02*
D03*
Y-351600D02*
D03*
X18441Y-139600D02*
D03*
X16441Y-143600D02*
D03*
X18441Y-147600D02*
D03*
X16441Y-151600D02*
D03*
X18441Y-163600D02*
D03*
X16441Y-167600D02*
D03*
X18441Y-171600D02*
D03*
X16441Y-191600D02*
D03*
X18441Y-195600D02*
D03*
X16441Y-199600D02*
D03*
X18441Y-203600D02*
D03*
X16441Y-215600D02*
D03*
X18441Y-219600D02*
D03*
X16441Y-223600D02*
D03*
X18441Y-235600D02*
D03*
Y-243600D02*
D03*
X16441Y-247600D02*
D03*
X18441Y-251600D02*
D03*
X16441Y-255600D02*
D03*
X18441Y-259600D02*
D03*
Y-267600D02*
D03*
X16441Y-271600D02*
D03*
X18441Y-275600D02*
D03*
X16441Y-279600D02*
D03*
X18441Y-291600D02*
D03*
Y-299600D02*
D03*
X16441Y-303600D02*
D03*
X18441Y-307600D02*
D03*
X16441Y-311600D02*
D03*
X18441Y-323600D02*
D03*
X16441Y-327600D02*
D03*
X18441Y-339600D02*
D03*
X16441Y-343600D02*
D03*
Y-351600D02*
D03*
X14441Y-139600D02*
D03*
X12441Y-143600D02*
D03*
X14441Y-147600D02*
D03*
X12441Y-151600D02*
D03*
X14441Y-163600D02*
D03*
X12441Y-167600D02*
D03*
X14441Y-171600D02*
D03*
X12441Y-191600D02*
D03*
X14441Y-195600D02*
D03*
X12441Y-199600D02*
D03*
X14441Y-203600D02*
D03*
X12441Y-215600D02*
D03*
X14441Y-219600D02*
D03*
X12441Y-223600D02*
D03*
X14441Y-243600D02*
D03*
X12441Y-247600D02*
D03*
X14441Y-251600D02*
D03*
X12441Y-255600D02*
D03*
X14441Y-259600D02*
D03*
Y-267600D02*
D03*
X12441Y-271600D02*
D03*
X14441Y-275600D02*
D03*
X12441Y-279600D02*
D03*
X14441Y-291600D02*
D03*
Y-299600D02*
D03*
X12441Y-303600D02*
D03*
X14441Y-307600D02*
D03*
X12441Y-311600D02*
D03*
X14441Y-323600D02*
D03*
X12441Y-327600D02*
D03*
X14441Y-331600D02*
D03*
X12441Y-343600D02*
D03*
Y-351600D02*
D03*
X10441Y-139600D02*
D03*
Y-163600D02*
D03*
Y-171600D02*
D03*
X8441Y-191600D02*
D03*
X10441Y-195600D02*
D03*
Y-203600D02*
D03*
Y-227600D02*
D03*
Y-243600D02*
D03*
X8441Y-247600D02*
D03*
X10441Y-251600D02*
D03*
Y-259600D02*
D03*
Y-267600D02*
D03*
Y-275600D02*
D03*
X8441Y-279600D02*
D03*
X10441Y-299600D02*
D03*
Y-323600D02*
D03*
Y-331600D02*
D03*
X8441Y-351600D02*
D03*
X6441Y-139600D02*
D03*
X4441Y-191600D02*
D03*
X6441Y-243600D02*
D03*
X4441Y-351600D02*
D03*
X2441Y-243600D02*
D03*
X441Y-351600D02*
D03*
X-3559Y-191600D02*
D03*
X-1559Y-243600D02*
D03*
X-3559Y-351600D02*
D03*
X-5559Y-139600D02*
D03*
X-7559Y-143600D02*
D03*
Y-167600D02*
D03*
Y-191600D02*
D03*
Y-199600D02*
D03*
Y-223600D02*
D03*
X-5559Y-227600D02*
D03*
Y-243600D02*
D03*
X-7559Y-247600D02*
D03*
Y-279600D02*
D03*
X-5559Y-299600D02*
D03*
X-7559Y-303600D02*
D03*
Y-327600D02*
D03*
Y-351600D02*
D03*
X-9559Y-139600D02*
D03*
Y-171600D02*
D03*
X-11559Y-191600D02*
D03*
X-9559Y-195600D02*
D03*
Y-227600D02*
D03*
Y-243600D02*
D03*
X-11559Y-247600D02*
D03*
X-9559Y-251600D02*
D03*
Y-275600D02*
D03*
X-11559Y-279600D02*
D03*
X-9559Y-299600D02*
D03*
Y-331600D02*
D03*
X-11559Y-351600D02*
D03*
X-13559Y-139600D02*
D03*
X-15559Y-191600D02*
D03*
X-13559Y-243600D02*
D03*
X-15559Y-351600D02*
D03*
X-19559Y-263600D02*
D03*
Y-351600D02*
D03*
X-23559Y-159600D02*
D03*
Y-191600D02*
D03*
X-21559Y-211600D02*
D03*
X-23559Y-263600D02*
D03*
X-21559Y-315600D02*
D03*
X-23559Y-351600D02*
D03*
X-25559Y-139600D02*
D03*
Y-155600D02*
D03*
Y-211600D02*
D03*
Y-259600D02*
D03*
Y-267600D02*
D03*
Y-299600D02*
D03*
Y-315600D02*
D03*
X234252Y-133742D02*
D03*
X263779Y-106151D02*
D03*
X71850Y-147638D02*
D03*
X75787Y-131890D02*
D03*
X623000Y-37402D02*
D03*
X610236Y-8858D02*
D03*
X609252Y-26575D02*
D03*
X98425Y-102362D02*
D03*
X89567D02*
D03*
X85630Y-313976D02*
D03*
X86614Y-258858D02*
D03*
X81693Y-205709D02*
D03*
X63976Y-227362D02*
D03*
X68898Y-285433D02*
D03*
X67913Y-340551D02*
D03*
X68573Y-179321D02*
D03*
X44291Y-252953D02*
D03*
Y-272638D02*
D03*
Y-326772D02*
D03*
Y-307087D02*
D03*
X26575Y-291339D02*
D03*
X31496Y-189961D02*
D03*
X44291Y-147638D02*
D03*
Y-167323D02*
D03*
Y-200787D02*
D03*
Y-220472D02*
D03*
X103409Y-141732D02*
D03*
X103347Y-110236D02*
D03*
X119095Y-126047D02*
D03*
X518701Y-104214D02*
D03*
X519587Y-134596D02*
D03*
X528543Y-104214D02*
D03*
X114173Y-83088D02*
D03*
X441929Y-122883D02*
D03*
X129921Y-79576D02*
D03*
X163071Y-390730D02*
D03*
X99410Y-50049D02*
D03*
X259285Y-390247D02*
D03*
X267204Y-390009D02*
D03*
X216162Y-390947D02*
D03*
X235144Y-390416D02*
D03*
X251456Y-390009D02*
D03*
X226063Y-390722D02*
D03*
X281201Y-390009D02*
D03*
X174941Y-390600D02*
D03*
X202441D02*
D03*
D251*
X348211Y-89891D02*
D03*
X357798Y-89963D02*
D03*
D253*
X99016Y-121653D02*
D03*
X103347D02*
D03*
X107677D02*
D03*
X99016Y-125984D02*
D03*
X103347D02*
D03*
X107677D02*
D03*
X99016Y-130315D02*
D03*
X103347D02*
D03*
X107677D02*
D03*
M02*
